FILE_TYPE = MACRO_DRAWING;
SET COLOR_WIRE YELLOW;
SET COLOR_PROP ORANGE;
SET COLOR_DOT WHITE;
SET COLOR_ARC YELLOW;
SET COLOR_BODY GREEN;
SET COLOR_NOTE PURPLE;
SET PROP_DISPLAY VALUE;
SET PAGE_NUMBER P58;
FORCEADD GENOA_SP5..28
(-8575 3425);
FORCEPROP 1 LAST LOCATION U26
J 0
(-8975 6600);
DISPLAY 0.489362 (-8975 6600);
PAINT SKYBLUE (-8975 6600);
FORCEPROP 0 LAST $SEC 28
J 0
(-8950 6825);
DISPLAY 0.680851 (-8950 6825);
PAINT MONO (-8950 6825);
DISPLAY INVISIBLE (-8950 6825);
FORCEPROP 0 LAST CDS_SEC 28
J 0
(-8950 6825);
DISPLAY 1.021277 (-8950 6825);
DISPLAY INVISIBLE (-8950 6825);
FORCEPROP 0 LASTPIN (-9125 6375) $PN A3
J 2
(-9135 6385);
DISPLAY 0.489362 (-9135 6385);
PAINT MONO (-9135 6385);
FORCEPROP 0 LASTPIN (-9125 6325) $PN A9
J 2
(-9135 6335);
DISPLAY 0.489362 (-9135 6335);
PAINT MONO (-9135 6335);
FORCEPROP 0 LASTPIN (-9125 6275) $PN A15
J 2
(-9135 6285);
DISPLAY 0.489362 (-9135 6285);
PAINT MONO (-9135 6285);
FORCEPROP 0 LASTPIN (-9125 6225) $PN A21
J 2
(-9135 6235);
DISPLAY 0.489362 (-9135 6235);
PAINT MONO (-9135 6235);
FORCEPROP 0 LASTPIN (-9125 6175) $PN A27
J 2
(-9135 6185);
DISPLAY 0.489362 (-9135 6185);
PAINT MONO (-9135 6185);
FORCEPROP 0 LASTPIN (-9125 6125) $PN A43
J 2
(-9135 6135);
DISPLAY 0.489362 (-9135 6135);
PAINT MONO (-9135 6135);
FORCEPROP 0 LASTPIN (-9125 6075) $PN A44
J 2
(-9135 6085);
DISPLAY 0.489362 (-9135 6085);
PAINT MONO (-9135 6085);
FORCEPROP 0 LASTPIN (-9125 6025) $PN A47
J 2
(-9135 6035);
DISPLAY 0.489362 (-9135 6035);
PAINT MONO (-9135 6035);
FORCEPROP 0 LASTPIN (-9125 5975) $PN A49
J 2
(-9135 5985);
DISPLAY 0.489362 (-9135 5985);
PAINT MONO (-9135 5985);
FORCEPROP 0 LASTPIN (-9125 5925) $PN A53
J 2
(-9135 5935);
DISPLAY 0.489362 (-9135 5935);
PAINT MONO (-9135 5935);
FORCEPROP 0 LASTPIN (-9125 5875) $PN A61
J 2
(-9135 5885);
DISPLAY 0.489362 (-9135 5885);
PAINT MONO (-9135 5885);
FORCEPROP 0 LASTPIN (-9125 5825) $PN A67
J 2
(-9135 5835);
DISPLAY 0.489362 (-9135 5835);
PAINT MONO (-9135 5835);
FORCEPROP 0 LASTPIN (-9125 5775) $PN A72
J 2
(-9135 5785);
DISPLAY 0.489362 (-9135 5785);
PAINT MONO (-9135 5785);
FORCEPROP 0 LASTPIN (-9125 5725) $PN A73
J 2
(-9135 5735);
DISPLAY 0.489362 (-9135 5735);
PAINT MONO (-9135 5735);
FORCEPROP 0 LASTPIN (-9125 5675) $PN B7
J 2
(-9135 5685);
DISPLAY 0.489362 (-9135 5685);
PAINT MONO (-9135 5685);
FORCEPROP 0 LASTPIN (-9125 5625) $PN B8
J 2
(-9135 5635);
DISPLAY 0.489362 (-9135 5635);
PAINT MONO (-9135 5635);
FORCEPROP 0 LASTPIN (-9125 5575) $PN B10
J 2
(-9135 5585);
DISPLAY 0.489362 (-9135 5585);
PAINT MONO (-9135 5585);
FORCEPROP 0 LASTPIN (-9125 5525) $PN B11
J 2
(-9135 5535);
DISPLAY 0.489362 (-9135 5535);
PAINT MONO (-9135 5535);
FORCEPROP 0 LASTPIN (-9125 5475) $PN B13
J 2
(-9135 5485);
DISPLAY 0.489362 (-9135 5485);
PAINT MONO (-9135 5485);
FORCEPROP 0 LASTPIN (-9125 5425) $PN B18
J 2
(-9135 5435);
DISPLAY 0.489362 (-9135 5435);
PAINT MONO (-9135 5435);
FORCEPROP 0 LASTPIN (-9125 5375) $PN B24
J 2
(-9135 5385);
DISPLAY 0.489362 (-9135 5385);
PAINT MONO (-9135 5385);
FORCEPROP 0 LASTPIN (-9125 5325) $PN B27
J 2
(-9135 5335);
DISPLAY 0.489362 (-9135 5335);
PAINT MONO (-9135 5335);
FORCEPROP 0 LASTPIN (-9125 5275) $PN B30
J 2
(-9135 5285);
DISPLAY 0.489362 (-9135 5285);
PAINT MONO (-9135 5285);
FORCEPROP 0 LASTPIN (-9125 5225) $PN B33
J 2
(-9135 5235);
DISPLAY 0.489362 (-9135 5235);
PAINT MONO (-9135 5235);
FORCEPROP 0 LASTPIN (-9125 5175) $PN B37
J 2
(-9135 5185);
DISPLAY 0.489362 (-9135 5185);
PAINT MONO (-9135 5185);
FORCEPROP 0 LASTPIN (-9125 5125) $PN B39
J 2
(-9135 5135);
DISPLAY 0.489362 (-9135 5135);
PAINT MONO (-9135 5135);
FORCEPROP 0 LASTPIN (-9125 5075) $PN B43
J 2
(-9135 5085);
DISPLAY 0.489362 (-9135 5085);
PAINT MONO (-9135 5085);
FORCEPROP 0 LASTPIN (-9125 5025) $PN B46
J 2
(-9135 5035);
DISPLAY 0.489362 (-9135 5035);
PAINT MONO (-9135 5035);
FORCEPROP 0 LASTPIN (-9125 4975) $PN B49
J 2
(-9135 4985);
DISPLAY 0.489362 (-9135 4985);
PAINT MONO (-9135 4985);
FORCEPROP 0 LASTPIN (-9125 4925) $PN B52
J 2
(-9135 4935);
DISPLAY 0.489362 (-9135 4935);
PAINT MONO (-9135 4935);
FORCEPROP 0 LASTPIN (-9125 4875) $PN B55
J 2
(-9135 4885);
DISPLAY 0.489362 (-9135 4885);
PAINT MONO (-9135 4885);
FORCEPROP 0 LASTPIN (-9125 4825) $PN B59
J 2
(-9135 4835);
DISPLAY 0.489362 (-9135 4835);
PAINT MONO (-9135 4835);
FORCEPROP 0 LASTPIN (-9125 4775) $PN B62
J 2
(-9135 4785);
DISPLAY 0.489362 (-9135 4785);
PAINT MONO (-9135 4785);
FORCEPROP 0 LASTPIN (-9125 4725) $PN B65
J 2
(-9135 4735);
DISPLAY 0.489362 (-9135 4735);
PAINT MONO (-9135 4735);
FORCEPROP 0 LASTPIN (-9125 4675) $PN B68
J 2
(-9135 4685);
DISPLAY 0.489362 (-9135 4685);
PAINT MONO (-9135 4685);
FORCEPROP 0 LASTPIN (-9125 4625) $PN B70
J 2
(-9135 4635);
DISPLAY 0.489362 (-9135 4635);
PAINT MONO (-9135 4635);
FORCEPROP 0 LASTPIN (-9125 4575) $PN C1
J 2
(-9135 4585);
DISPLAY 0.489362 (-9135 4585);
PAINT MONO (-9135 4585);
FORCEPROP 0 LASTPIN (-9125 4525) $PN C5
J 2
(-9135 4535);
DISPLAY 0.489362 (-9135 4535);
PAINT MONO (-9135 4535);
FORCEPROP 0 LASTPIN (-9125 4475) $PN C8
J 2
(-9135 4485);
DISPLAY 0.489362 (-9135 4485);
PAINT MONO (-9135 4485);
FORCEPROP 0 LASTPIN (-9125 4425) $PN C10
J 2
(-9135 4435);
DISPLAY 0.489362 (-9135 4435);
PAINT MONO (-9135 4435);
FORCEPROP 0 LASTPIN (-9125 4375) $PN C11
J 2
(-9135 4385);
DISPLAY 0.489362 (-9135 4385);
PAINT MONO (-9135 4385);
FORCEPROP 0 LASTPIN (-9125 4325) $PN C13
J 2
(-9135 4335);
DISPLAY 0.489362 (-9135 4335);
PAINT MONO (-9135 4335);
FORCEPROP 0 LASTPIN (-9125 4275) $PN C15
J 2
(-9135 4285);
DISPLAY 0.489362 (-9135 4285);
PAINT MONO (-9135 4285);
FORCEPROP 0 LASTPIN (-9125 4225) $PN C21
J 2
(-9135 4235);
DISPLAY 0.489362 (-9135 4235);
PAINT MONO (-9135 4235);
FORCEPROP 0 LASTPIN (-9125 4175) $PN C24
J 2
(-9135 4185);
DISPLAY 0.489362 (-9135 4185);
PAINT MONO (-9135 4185);
FORCEPROP 0 LASTPIN (-9125 4125) $PN C27
J 2
(-9135 4135);
DISPLAY 0.489362 (-9135 4135);
PAINT MONO (-9135 4135);
FORCEPROP 0 LASTPIN (-9125 4075) $PN C30
J 2
(-9135 4085);
DISPLAY 0.489362 (-9135 4085);
PAINT MONO (-9135 4085);
FORCEPROP 0 LASTPIN (-9125 4025) $PN C36
J 2
(-9135 4035);
DISPLAY 0.489362 (-9135 4035);
PAINT MONO (-9135 4035);
FORCEPROP 0 LASTPIN (-9125 3975) $PN C40
J 2
(-9135 3985);
DISPLAY 0.489362 (-9135 3985);
PAINT MONO (-9135 3985);
FORCEPROP 0 LASTPIN (-9125 3925) $PN C43
J 2
(-9135 3935);
DISPLAY 0.489362 (-9135 3935);
PAINT MONO (-9135 3935);
FORCEPROP 0 LASTPIN (-9125 3875) $PN C46
J 2
(-9135 3885);
DISPLAY 0.489362 (-9135 3885);
PAINT MONO (-9135 3885);
FORCEPROP 0 LASTPIN (-9125 3825) $PN C49
J 2
(-9135 3835);
DISPLAY 0.489362 (-9135 3835);
PAINT MONO (-9135 3835);
FORCEPROP 0 LASTPIN (-9125 3775) $PN C52
J 2
(-9135 3785);
DISPLAY 0.489362 (-9135 3785);
PAINT MONO (-9135 3785);
FORCEPROP 0 LASTPIN (-9125 3725) $PN C55
J 2
(-9135 3735);
DISPLAY 0.489362 (-9135 3735);
PAINT MONO (-9135 3735);
FORCEPROP 0 LASTPIN (-9125 3675) $PN C56
J 2
(-9135 3685);
DISPLAY 0.489362 (-9135 3685);
PAINT MONO (-9135 3685);
FORCEPROP 0 LASTPIN (-9125 3625) $PN C57
J 2
(-9135 3635);
DISPLAY 0.489362 (-9135 3635);
PAINT MONO (-9135 3635);
FORCEPROP 0 LASTPIN (-9125 3575) $PN C61
J 2
(-9135 3585);
DISPLAY 0.489362 (-9135 3585);
PAINT MONO (-9135 3585);
FORCEPROP 0 LASTPIN (-9125 3525) $PN C64
J 2
(-9135 3535);
DISPLAY 0.489362 (-9135 3535);
PAINT MONO (-9135 3535);
FORCEPROP 0 LASTPIN (-9125 3475) $PN C67
J 2
(-9135 3485);
DISPLAY 0.489362 (-9135 3485);
PAINT MONO (-9135 3485);
FORCEPROP 0 LASTPIN (-9125 3425) $PN C69
J 2
(-9135 3435);
DISPLAY 0.489362 (-9135 3435);
PAINT MONO (-9135 3435);
FORCEPROP 0 LASTPIN (-9125 3375) $PN C71
J 2
(-9135 3385);
DISPLAY 0.489362 (-9135 3385);
PAINT MONO (-9135 3385);
FORCEPROP 0 LASTPIN (-9125 3325) $PN C73
J 2
(-9135 3335);
DISPLAY 0.489362 (-9135 3335);
PAINT MONO (-9135 3335);
FORCEPROP 0 LASTPIN (-9125 3275) $PN C75
J 2
(-9135 3285);
DISPLAY 0.489362 (-9135 3285);
PAINT MONO (-9135 3285);
FORCEPROP 0 LASTPIN (-9125 3225) $PN D2
J 2
(-9135 3235);
DISPLAY 0.489362 (-9135 3235);
PAINT MONO (-9135 3235);
FORCEPROP 0 LASTPIN (-9125 3175) $PN D3
J 2
(-9135 3185);
DISPLAY 0.489362 (-9135 3185);
PAINT MONO (-9135 3185);
FORCEPROP 0 LASTPIN (-9125 3125) $PN D5
J 2
(-9135 3135);
DISPLAY 0.489362 (-9135 3135);
PAINT MONO (-9135 3135);
FORCEPROP 0 LASTPIN (-9125 3075) $PN D6
J 2
(-9135 3085);
DISPLAY 0.489362 (-9135 3085);
PAINT MONO (-9135 3085);
FORCEPROP 0 LASTPIN (-9125 3025) $PN D9
J 2
(-9135 3035);
DISPLAY 0.489362 (-9135 3035);
PAINT MONO (-9135 3035);
FORCEPROP 0 LASTPIN (-9125 2975) $PN D10
J 2
(-9135 2985);
DISPLAY 0.489362 (-9135 2985);
PAINT MONO (-9135 2985);
FORCEPROP 0 LASTPIN (-9125 2925) $PN D12
J 2
(-9135 2935);
DISPLAY 0.489362 (-9135 2935);
PAINT MONO (-9135 2935);
FORCEPROP 0 LASTPIN (-9125 2875) $PN D13
J 2
(-9135 2885);
DISPLAY 0.489362 (-9135 2885);
PAINT MONO (-9135 2885);
FORCEPROP 0 LASTPIN (-9125 2825) $PN D16
J 2
(-9135 2835);
DISPLAY 0.489362 (-9135 2835);
PAINT MONO (-9135 2835);
FORCEPROP 0 LASTPIN (-9125 2775) $PN D17
J 2
(-9135 2785);
DISPLAY 0.489362 (-9135 2785);
PAINT MONO (-9135 2785);
FORCEPROP 0 LASTPIN (-9125 2725) $PN D19
J 2
(-9135 2735);
DISPLAY 0.489362 (-9135 2735);
PAINT MONO (-9135 2735);
FORCEPROP 0 LASTPIN (-9125 2675) $PN D20
J 2
(-9135 2685);
DISPLAY 0.489362 (-9135 2685);
PAINT MONO (-9135 2685);
FORCEPROP 0 LASTPIN (-9125 2625) $PN D21
J 2
(-9135 2635);
DISPLAY 0.489362 (-9135 2635);
PAINT MONO (-9135 2635);
FORCEPROP 0 LASTPIN (-9125 2575) $PN D24
J 2
(-9135 2585);
DISPLAY 0.489362 (-9135 2585);
PAINT MONO (-9135 2585);
FORCEPROP 0 LASTPIN (-9125 2525) $PN D25
J 2
(-9135 2535);
DISPLAY 0.489362 (-9135 2535);
PAINT MONO (-9135 2535);
FORCEPROP 0 LASTPIN (-9125 2475) $PN D26
J 2
(-9135 2485);
DISPLAY 0.489362 (-9135 2485);
PAINT MONO (-9135 2485);
FORCEPROP 0 LASTPIN (-9125 2425) $PN D27
J 2
(-9135 2435);
DISPLAY 0.489362 (-9135 2435);
PAINT MONO (-9135 2435);
FORCEPROP 0 LASTPIN (-9125 2375) $PN D28
J 2
(-9135 2385);
DISPLAY 0.489362 (-9135 2385);
PAINT MONO (-9135 2385);
FORCEPROP 0 LASTPIN (-9125 2325) $PN D29
J 2
(-9135 2335);
DISPLAY 0.489362 (-9135 2335);
PAINT MONO (-9135 2335);
FORCEPROP 0 LASTPIN (-9125 2275) $PN D30
J 2
(-9135 2285);
DISPLAY 0.489362 (-9135 2285);
PAINT MONO (-9135 2285);
FORCEPROP 0 LASTPIN (-9125 2225) $PN D31
J 2
(-9135 2235);
DISPLAY 0.489362 (-9135 2235);
PAINT MONO (-9135 2235);
FORCEPROP 0 LASTPIN (-9125 2175) $PN D35
J 2
(-9135 2185);
DISPLAY 0.489362 (-9135 2185);
PAINT MONO (-9135 2185);
FORCEPROP 0 LASTPIN (-9125 2125) $PN D37
J 2
(-9135 2135);
DISPLAY 0.489362 (-9135 2135);
PAINT MONO (-9135 2135);
FORCEPROP 0 LASTPIN (-9125 2075) $PN D39
J 2
(-9135 2085);
DISPLAY 0.489362 (-9135 2085);
PAINT MONO (-9135 2085);
FORCEPROP 0 LASTPIN (-9125 2025) $PN D40
J 2
(-9135 2035);
DISPLAY 0.489362 (-9135 2035);
PAINT MONO (-9135 2035);
FORCEPROP 0 LASTPIN (-9125 1975) $PN D41
J 2
(-9135 1985);
DISPLAY 0.489362 (-9135 1985);
PAINT MONO (-9135 1985);
FORCEPROP 0 LASTPIN (-9125 1925) $PN D42
J 2
(-9135 1935);
DISPLAY 0.489362 (-9135 1935);
PAINT MONO (-9135 1935);
FORCEPROP 0 LASTPIN (-9125 1875) $PN D43
J 2
(-9135 1885);
DISPLAY 0.489362 (-9135 1885);
PAINT MONO (-9135 1885);
FORCEPROP 0 LASTPIN (-9125 1825) $PN D44
J 2
(-9135 1835);
DISPLAY 0.489362 (-9135 1835);
PAINT MONO (-9135 1835);
FORCEPROP 0 LASTPIN (-9125 1775) $PN D45
J 2
(-9135 1785);
DISPLAY 0.489362 (-9135 1785);
PAINT MONO (-9135 1785);
FORCEPROP 0 LASTPIN (-9125 1725) $PN D46
J 2
(-9135 1735);
DISPLAY 0.489362 (-9135 1735);
PAINT MONO (-9135 1735);
FORCEPROP 0 LASTPIN (-9125 1675) $PN D47
J 2
(-9135 1685);
DISPLAY 0.489362 (-9135 1685);
PAINT MONO (-9135 1685);
FORCEPROP 0 LASTPIN (-9125 1625) $PN D48
J 2
(-9135 1635);
DISPLAY 0.489362 (-9135 1635);
PAINT MONO (-9135 1635);
FORCEPROP 0 LASTPIN (-9125 1575) $PN D49
J 2
(-9135 1585);
DISPLAY 0.489362 (-9135 1585);
PAINT MONO (-9135 1585);
FORCEPROP 0 LASTPIN (-9125 1525) $PN D50
J 2
(-9135 1535);
DISPLAY 0.489362 (-9135 1535);
PAINT MONO (-9135 1535);
FORCEPROP 0 LASTPIN (-9125 1475) $PN D51
J 2
(-9135 1485);
DISPLAY 0.489362 (-9135 1485);
PAINT MONO (-9135 1485);
FORCEPROP 0 LASTPIN (-9125 1425) $PN D52
J 2
(-9135 1435);
DISPLAY 0.489362 (-9135 1435);
PAINT MONO (-9135 1435);
FORCEPROP 0 LASTPIN (-9125 1375) $PN D53
J 2
(-9135 1385);
DISPLAY 0.489362 (-9135 1385);
PAINT MONO (-9135 1385);
FORCEPROP 0 LASTPIN (-9125 1325) $PN D54
J 2
(-9135 1335);
DISPLAY 0.489362 (-9135 1335);
PAINT MONO (-9135 1335);
FORCEPROP 0 LASTPIN (-9125 1275) $PN D57
J 2
(-9135 1285);
DISPLAY 0.489362 (-9135 1285);
PAINT MONO (-9135 1285);
FORCEPROP 0 LASTPIN (-9125 1225) $PN D59
J 2
(-9135 1235);
DISPLAY 0.489362 (-9135 1235);
PAINT MONO (-9135 1235);
FORCEPROP 0 LASTPIN (-9125 1175) $PN D60
J 2
(-9135 1185);
DISPLAY 0.489362 (-9135 1185);
PAINT MONO (-9135 1185);
FORCEPROP 0 LASTPIN (-9125 1125) $PN D61
J 2
(-9135 1135);
DISPLAY 0.489362 (-9135 1135);
PAINT MONO (-9135 1135);
FORCEPROP 0 LASTPIN (-9125 1075) $PN D63
J 2
(-9135 1085);
DISPLAY 0.489362 (-9135 1085);
PAINT MONO (-9135 1085);
FORCEPROP 0 LASTPIN (-9125 1025) $PN D64
J 2
(-9135 1035);
DISPLAY 0.489362 (-9135 1035);
PAINT MONO (-9135 1035);
FORCEPROP 0 LASTPIN (-9125 975) $PN D66
J 2
(-9135 985);
DISPLAY 0.489362 (-9135 985);
PAINT MONO (-9135 985);
FORCEPROP 0 LASTPIN (-9125 925) $PN D67
J 2
(-9135 935);
DISPLAY 0.489362 (-9135 935);
PAINT MONO (-9135 935);
FORCEPROP 0 LASTPIN (-9125 875) $PN D70
J 2
(-9135 885);
DISPLAY 0.489362 (-9135 885);
PAINT MONO (-9135 885);
FORCEPROP 0 LASTPIN (-9125 825) $PN D71
J 2
(-9135 835);
DISPLAY 0.489362 (-9135 835);
PAINT MONO (-9135 835);
FORCEPROP 0 LASTPIN (-9125 775) $PN D73
J 2
(-9135 785);
DISPLAY 0.489362 (-9135 785);
PAINT MONO (-9135 785);
FORCEPROP 0 LASTPIN (-9125 725) $PN D74
J 2
(-9135 735);
DISPLAY 0.489362 (-9135 735);
PAINT MONO (-9135 735);
FORCEPROP 0 LASTPIN (-9125 675) $PN E1
J 2
(-9135 685);
DISPLAY 0.489362 (-9135 685);
PAINT MONO (-9135 685);
FORCEPROP 0 LASTPIN (-9125 625) $PN E3
J 2
(-9135 635);
DISPLAY 0.489362 (-9135 635);
PAINT MONO (-9135 635);
FORCEPROP 0 LASTPIN (-9125 575) $PN E6
J 2
(-9135 585);
DISPLAY 0.489362 (-9135 585);
PAINT MONO (-9135 585);
FORCEPROP 0 LASTPIN (-9125 525) $PN E7
J 2
(-9135 535);
DISPLAY 0.489362 (-9135 535);
PAINT MONO (-9135 535);
FORCEPROP 0 LASTPIN (-9125 475) $PN E8
J 2
(-9135 485);
DISPLAY 0.489362 (-9135 485);
PAINT MONO (-9135 485);
FORCEPROP 0 LASTPIN (-8025 6375) $PN E10
J 0
(-8015 6385);
DISPLAY 0.489362 (-8015 6385);
PAINT MONO (-8015 6385);
FORCEPROP 0 LASTPIN (-8025 6325) $PN E13
J 0
(-8015 6335);
DISPLAY 0.489362 (-8015 6335);
PAINT MONO (-8015 6335);
FORCEPROP 0 LASTPIN (-8025 6275) $PN E14
J 0
(-8015 6285);
DISPLAY 0.489362 (-8015 6285);
PAINT MONO (-8015 6285);
FORCEPROP 0 LASTPIN (-8025 6225) $PN E15
J 0
(-8015 6235);
DISPLAY 0.489362 (-8015 6235);
PAINT MONO (-8015 6235);
FORCEPROP 0 LASTPIN (-8025 6175) $PN E17
J 0
(-8015 6185);
DISPLAY 0.489362 (-8015 6185);
PAINT MONO (-8015 6185);
FORCEPROP 0 LASTPIN (-8025 6125) $PN E18
J 0
(-8015 6135);
DISPLAY 0.489362 (-8015 6135);
PAINT MONO (-8015 6135);
FORCEPROP 0 LASTPIN (-8025 6075) $PN E20
J 0
(-8015 6085);
DISPLAY 0.489362 (-8015 6085);
PAINT MONO (-8015 6085);
FORCEPROP 0 LASTPIN (-8025 6025) $PN E21
J 0
(-8015 6035);
DISPLAY 0.489362 (-8015 6035);
PAINT MONO (-8015 6035);
FORCEPROP 0 LASTPIN (-8025 5975) $PN E52
J 0
(-8015 5985);
DISPLAY 0.489362 (-8015 5985);
PAINT MONO (-8015 5985);
FORCEPROP 0 LASTPIN (-8025 5925) $PN E53
J 0
(-8015 5935);
DISPLAY 0.489362 (-8015 5935);
PAINT MONO (-8015 5935);
FORCEPROP 0 LASTPIN (-8025 5875) $PN E55
J 0
(-8015 5885);
DISPLAY 0.489362 (-8015 5885);
PAINT MONO (-8015 5885);
FORCEPROP 0 LASTPIN (-8025 5825) $PN E56
J 0
(-8015 5835);
DISPLAY 0.489362 (-8015 5835);
PAINT MONO (-8015 5835);
FORCEPROP 0 LASTPIN (-8025 5775) $PN E58
J 0
(-8015 5785);
DISPLAY 0.489362 (-8015 5785);
PAINT MONO (-8015 5785);
FORCEPROP 0 LASTPIN (-8025 5725) $PN E59
J 0
(-8015 5735);
DISPLAY 0.489362 (-8015 5735);
PAINT MONO (-8015 5735);
FORCEPROP 0 LASTPIN (-8025 5675) $PN E61
J 0
(-8015 5685);
DISPLAY 0.489362 (-8015 5685);
PAINT MONO (-8015 5685);
FORCEPROP 0 LASTPIN (-8025 5625) $PN E62
J 0
(-8015 5635);
DISPLAY 0.489362 (-8015 5635);
PAINT MONO (-8015 5635);
FORCEPROP 0 LASTPIN (-8025 5575) $PN E63
J 0
(-8015 5585);
DISPLAY 0.489362 (-8015 5585);
PAINT MONO (-8015 5585);
FORCEPROP 0 LASTPIN (-8025 5525) $PN E65
J 0
(-8015 5535);
DISPLAY 0.489362 (-8015 5535);
PAINT MONO (-8015 5535);
FORCEPROP 0 LASTPIN (-8025 5475) $PN E66
J 0
(-8015 5485);
DISPLAY 0.489362 (-8015 5485);
PAINT MONO (-8015 5485);
FORCEPROP 0 LASTPIN (-8025 5425) $PN E68
J 0
(-8015 5435);
DISPLAY 0.489362 (-8015 5435);
PAINT MONO (-8015 5435);
FORCEPROP 0 LASTPIN (-8025 5375) $PN E69
J 0
(-8015 5385);
DISPLAY 0.489362 (-8015 5385);
PAINT MONO (-8015 5385);
FORCEPROP 0 LASTPIN (-8025 5325) $PN E70
J 0
(-8015 5335);
DISPLAY 0.489362 (-8015 5335);
PAINT MONO (-8015 5335);
FORCEPROP 0 LASTPIN (-8025 5275) $PN E72
J 0
(-8015 5285);
DISPLAY 0.489362 (-8015 5285);
PAINT MONO (-8015 5285);
FORCEPROP 0 LASTPIN (-8025 5225) $PN E73
J 0
(-8015 5235);
DISPLAY 0.489362 (-8015 5235);
PAINT MONO (-8015 5235);
FORCEPROP 0 LASTPIN (-8025 5175) $PN E75
J 0
(-8015 5185);
DISPLAY 0.489362 (-8015 5185);
PAINT MONO (-8015 5185);
FORCEPROP 0 LASTPIN (-8025 5125) $PN F3
J 0
(-8015 5135);
DISPLAY 0.489362 (-8015 5135);
PAINT MONO (-8015 5135);
FORCEPROP 0 LASTPIN (-8025 5075) $PN F5
J 0
(-8015 5085);
DISPLAY 0.489362 (-8015 5085);
PAINT MONO (-8015 5085);
FORCEPROP 0 LASTPIN (-8025 5025) $PN F8
J 0
(-8015 5035);
DISPLAY 0.489362 (-8015 5035);
PAINT MONO (-8015 5035);
FORCEPROP 0 LASTPIN (-8025 4975) $PN F10
J 0
(-8015 4985);
DISPLAY 0.489362 (-8015 4985);
PAINT MONO (-8015 4985);
FORCEPROP 0 LASTPIN (-8025 4925) $PN F12
J 0
(-8015 4935);
DISPLAY 0.489362 (-8015 4935);
PAINT MONO (-8015 4935);
FORCEPROP 0 LASTPIN (-8025 4875) $PN F15
J 0
(-8015 4885);
DISPLAY 0.489362 (-8015 4885);
PAINT MONO (-8015 4885);
FORCEPROP 0 LASTPIN (-8025 4825) $PN F17
J 0
(-8015 4835);
DISPLAY 0.489362 (-8015 4835);
PAINT MONO (-8015 4835);
FORCEPROP 0 LASTPIN (-8025 4775) $PN F19
J 0
(-8015 4785);
DISPLAY 0.489362 (-8015 4785);
PAINT MONO (-8015 4785);
FORCEPROP 0 LASTPIN (-8025 4725) $PN F23
J 0
(-8015 4735);
DISPLAY 0.489362 (-8015 4735);
PAINT MONO (-8015 4735);
FORCEPROP 0 LASTPIN (-8025 4675) $PN F24
J 0
(-8015 4685);
DISPLAY 0.489362 (-8015 4685);
PAINT MONO (-8015 4685);
FORCEPROP 0 LASTPIN (-8025 4625) $PN F26
J 0
(-8015 4635);
DISPLAY 0.489362 (-8015 4635);
PAINT MONO (-8015 4635);
FORCEPROP 0 LASTPIN (-8025 4575) $PN F27
J 0
(-8015 4585);
DISPLAY 0.489362 (-8015 4585);
PAINT MONO (-8015 4585);
FORCEPROP 0 LASTPIN (-8025 4525) $PN F29
J 0
(-8015 4535);
DISPLAY 0.489362 (-8015 4535);
PAINT MONO (-8015 4535);
FORCEPROP 0 LASTPIN (-8025 4475) $PN F30
J 0
(-8015 4485);
DISPLAY 0.489362 (-8015 4485);
PAINT MONO (-8015 4485);
FORCEPROP 0 LASTPIN (-8025 4425) $PN F32
J 0
(-8015 4435);
DISPLAY 0.489362 (-8015 4435);
PAINT MONO (-8015 4435);
FORCEPROP 0 LASTPIN (-8025 4375) $PN F33
J 0
(-8015 4385);
DISPLAY 0.489362 (-8015 4385);
PAINT MONO (-8015 4385);
FORCEPROP 0 LASTPIN (-8025 4325) $PN F35
J 0
(-8015 4335);
DISPLAY 0.489362 (-8015 4335);
PAINT MONO (-8015 4335);
FORCEPROP 0 LASTPIN (-8025 4275) $PN F36
J 0
(-8015 4285);
DISPLAY 0.489362 (-8015 4285);
PAINT MONO (-8015 4285);
FORCEPROP 0 LASTPIN (-8025 4225) $PN F37
J 0
(-8015 4235);
DISPLAY 0.489362 (-8015 4235);
PAINT MONO (-8015 4235);
FORCEPROP 0 LASTPIN (-8025 4175) $PN F39
J 0
(-8015 4185);
DISPLAY 0.489362 (-8015 4185);
PAINT MONO (-8015 4185);
FORCEPROP 0 LASTPIN (-8025 4125) $PN F40
J 0
(-8015 4135);
DISPLAY 0.489362 (-8015 4135);
PAINT MONO (-8015 4135);
FORCEPROP 0 LASTPIN (-8025 4075) $PN F41
J 0
(-8015 4085);
DISPLAY 0.489362 (-8015 4085);
PAINT MONO (-8015 4085);
FORCEPROP 0 LASTPIN (-8025 4025) $PN F43
J 0
(-8015 4035);
DISPLAY 0.489362 (-8015 4035);
PAINT MONO (-8015 4035);
FORCEPROP 0 LASTPIN (-8025 3975) $PN F44
J 0
(-8015 3985);
DISPLAY 0.489362 (-8015 3985);
PAINT MONO (-8015 3985);
FORCEPROP 0 LASTPIN (-8025 3925) $PN F46
J 0
(-8015 3935);
DISPLAY 0.489362 (-8015 3935);
PAINT MONO (-8015 3935);
FORCEPROP 0 LASTPIN (-8025 3875) $PN F47
J 0
(-8015 3885);
DISPLAY 0.489362 (-8015 3885);
PAINT MONO (-8015 3885);
FORCEPROP 0 LASTPIN (-8025 3825) $PN F49
J 0
(-8015 3835);
DISPLAY 0.489362 (-8015 3835);
PAINT MONO (-8015 3835);
FORCEPROP 0 LASTPIN (-8025 3775) $PN F50
J 0
(-8015 3785);
DISPLAY 0.489362 (-8015 3785);
PAINT MONO (-8015 3785);
FORCEPROP 0 LASTPIN (-8025 3725) $PN F52
J 0
(-8015 3735);
DISPLAY 0.489362 (-8015 3735);
PAINT MONO (-8015 3735);
FORCEPROP 0 LASTPIN (-8025 3675) $PN F53
J 0
(-8015 3685);
DISPLAY 0.489362 (-8015 3685);
PAINT MONO (-8015 3685);
FORCEPROP 0 LASTPIN (-8025 3625) $PN F57
J 0
(-8015 3635);
DISPLAY 0.489362 (-8015 3635);
PAINT MONO (-8015 3635);
FORCEPROP 0 LASTPIN (-8025 3575) $PN F59
J 0
(-8015 3585);
DISPLAY 0.489362 (-8015 3585);
PAINT MONO (-8015 3585);
FORCEPROP 0 LASTPIN (-8025 3525) $PN F61
J 0
(-8015 3535);
DISPLAY 0.489362 (-8015 3535);
PAINT MONO (-8015 3535);
FORCEPROP 0 LASTPIN (-8025 3475) $PN F64
J 0
(-8015 3485);
DISPLAY 0.489362 (-8015 3485);
PAINT MONO (-8015 3485);
FORCEPROP 0 LASTPIN (-8025 3425) $PN F66
J 0
(-8015 3435);
DISPLAY 0.489362 (-8015 3435);
PAINT MONO (-8015 3435);
FORCEPROP 0 LASTPIN (-8025 3375) $PN F68
J 0
(-8015 3385);
DISPLAY 0.489362 (-8015 3385);
PAINT MONO (-8015 3385);
FORCEPROP 0 LASTPIN (-8025 3325) $PN F71
J 0
(-8015 3335);
DISPLAY 0.489362 (-8015 3335);
PAINT MONO (-8015 3335);
FORCEPROP 0 LASTPIN (-8025 3275) $PN F73
J 0
(-8015 3285);
DISPLAY 0.489362 (-8015 3285);
PAINT MONO (-8015 3285);
FORCEPROP 0 LASTPIN (-8025 3225) $PN G1
J 0
(-8015 3235);
DISPLAY 0.489362 (-8015 3235);
PAINT MONO (-8015 3235);
FORCEPROP 0 LASTPIN (-8025 3175) $PN G4
J 0
(-8015 3185);
DISPLAY 0.489362 (-8015 3185);
PAINT MONO (-8015 3185);
FORCEPROP 0 LASTPIN (-8025 3125) $PN G6
J 0
(-8015 3135);
DISPLAY 0.489362 (-8015 3135);
PAINT MONO (-8015 3135);
FORCEPROP 0 LASTPIN (-8025 3075) $PN G8
J 0
(-8015 3085);
DISPLAY 0.489362 (-8015 3085);
PAINT MONO (-8015 3085);
FORCEPROP 0 LASTPIN (-8025 3025) $PN G11
J 0
(-8015 3035);
DISPLAY 0.489362 (-8015 3035);
PAINT MONO (-8015 3035);
FORCEPROP 0 LASTPIN (-8025 2975) $PN G13
J 0
(-8015 2985);
DISPLAY 0.489362 (-8015 2985);
PAINT MONO (-8015 2985);
FORCEPROP 0 LASTPIN (-8025 2925) $PN G15
J 0
(-8015 2935);
DISPLAY 0.489362 (-8015 2935);
PAINT MONO (-8015 2935);
FORCEPROP 0 LASTPIN (-8025 2875) $PN G18
J 0
(-8015 2885);
DISPLAY 0.489362 (-8015 2885);
PAINT MONO (-8015 2885);
FORCEPROP 0 LASTPIN (-8025 2825) $PN G20
J 0
(-8015 2835);
DISPLAY 0.489362 (-8015 2835);
PAINT MONO (-8015 2835);
FORCEPROP 0 LASTPIN (-8025 2775) $PN G22
J 0
(-8015 2785);
DISPLAY 0.489362 (-8015 2785);
PAINT MONO (-8015 2785);
FORCEPROP 0 LASTPIN (-8025 2725) $PN G25
J 0
(-8015 2735);
DISPLAY 0.489362 (-8015 2735);
PAINT MONO (-8015 2735);
FORCEPROP 0 LASTPIN (-8025 2675) $PN G28
J 0
(-8015 2685);
DISPLAY 0.489362 (-8015 2685);
PAINT MONO (-8015 2685);
FORCEPROP 0 LASTPIN (-8025 2625) $PN G31
J 0
(-8015 2635);
DISPLAY 0.489362 (-8015 2635);
PAINT MONO (-8015 2635);
FORCEPROP 0 LASTPIN (-8025 2575) $PN G34
J 0
(-8015 2585);
DISPLAY 0.489362 (-8015 2585);
PAINT MONO (-8015 2585);
FORCEPROP 0 LASTPIN (-8025 2525) $PN G42
J 0
(-8015 2535);
DISPLAY 0.489362 (-8015 2535);
PAINT MONO (-8015 2535);
FORCEPROP 0 LASTPIN (-8025 2475) $PN G45
J 0
(-8015 2485);
DISPLAY 0.489362 (-8015 2485);
PAINT MONO (-8015 2485);
FORCEPROP 0 LASTPIN (-8025 2425) $PN G48
J 0
(-8015 2435);
DISPLAY 0.489362 (-8015 2435);
PAINT MONO (-8015 2435);
FORCEPROP 0 LASTPIN (-8025 2375) $PN G51
J 0
(-8015 2385);
DISPLAY 0.489362 (-8015 2385);
PAINT MONO (-8015 2385);
FORCEPROP 0 LASTPIN (-8025 2325) $PN G54
J 0
(-8015 2335);
DISPLAY 0.489362 (-8015 2335);
PAINT MONO (-8015 2335);
FORCEPROP 0 LASTPIN (-8025 2275) $PN G56
J 0
(-8015 2285);
DISPLAY 0.489362 (-8015 2285);
PAINT MONO (-8015 2285);
FORCEPROP 0 LASTPIN (-8025 2225) $PN G58
J 0
(-8015 2235);
DISPLAY 0.489362 (-8015 2235);
PAINT MONO (-8015 2235);
FORCEPROP 0 LASTPIN (-8025 2175) $PN G61
J 0
(-8015 2185);
DISPLAY 0.489362 (-8015 2185);
PAINT MONO (-8015 2185);
FORCEPROP 0 LASTPIN (-8025 2125) $PN G63
J 0
(-8015 2135);
DISPLAY 0.489362 (-8015 2135);
PAINT MONO (-8015 2135);
FORCEPROP 0 LASTPIN (-8025 2075) $PN G65
J 0
(-8015 2085);
DISPLAY 0.489362 (-8015 2085);
PAINT MONO (-8015 2085);
FORCEPROP 0 LASTPIN (-8025 2025) $PN G68
J 0
(-8015 2035);
DISPLAY 0.489362 (-8015 2035);
PAINT MONO (-8015 2035);
FORCEPROP 0 LASTPIN (-8025 1975) $PN G70
J 0
(-8015 1985);
DISPLAY 0.489362 (-8015 1985);
PAINT MONO (-8015 1985);
FORCEPROP 0 LASTPIN (-8025 1925) $PN G72
J 0
(-8015 1935);
DISPLAY 0.489362 (-8015 1935);
PAINT MONO (-8015 1935);
FORCEPROP 0 LASTPIN (-8025 1875) $PN G75
J 0
(-8015 1885);
DISPLAY 0.489362 (-8015 1885);
PAINT MONO (-8015 1885);
FORCEPROP 0 LASTPIN (-8025 1825) $PN H3
J 0
(-8015 1835);
DISPLAY 0.489362 (-8015 1835);
PAINT MONO (-8015 1835);
FORCEPROP 0 LASTPIN (-8025 1775) $PN H8
J 0
(-8015 1785);
DISPLAY 0.489362 (-8015 1785);
PAINT MONO (-8015 1785);
FORCEPROP 0 LASTPIN (-8025 1725) $PN H10
J 0
(-8015 1735);
DISPLAY 0.489362 (-8015 1735);
PAINT MONO (-8015 1735);
FORCEPROP 0 LASTPIN (-8025 1675) $PN H15
J 0
(-8015 1685);
DISPLAY 0.489362 (-8015 1685);
PAINT MONO (-8015 1685);
FORCEPROP 0 LASTPIN (-8025 1625) $PN H17
J 0
(-8015 1635);
DISPLAY 0.489362 (-8015 1635);
PAINT MONO (-8015 1635);
FORCEPROP 0 LASTPIN (-8025 1575) $PN H22
J 0
(-8015 1585);
DISPLAY 0.489362 (-8015 1585);
PAINT MONO (-8015 1585);
FORCEPROP 0 LASTPIN (-8025 1525) $PN H25
J 0
(-8015 1535);
DISPLAY 0.489362 (-8015 1535);
PAINT MONO (-8015 1535);
FORCEPROP 0 LASTPIN (-8025 1475) $PN H28
J 0
(-8015 1485);
DISPLAY 0.489362 (-8015 1485);
PAINT MONO (-8015 1485);
FORCEPROP 0 LASTPIN (-8025 1425) $PN H31
J 0
(-8015 1435);
DISPLAY 0.489362 (-8015 1435);
PAINT MONO (-8015 1435);
FORCEPROP 0 LASTPIN (-8025 1375) $PN H34
J 0
(-8015 1385);
DISPLAY 0.489362 (-8015 1385);
PAINT MONO (-8015 1385);
FORCEPROP 0 LASTPIN (-8025 1325) $PN H37
J 0
(-8015 1335);
DISPLAY 0.489362 (-8015 1335);
PAINT MONO (-8015 1335);
FORCEPROP 0 LASTPIN (-8025 1275) $PN H39
J 0
(-8015 1285);
DISPLAY 0.489362 (-8015 1285);
PAINT MONO (-8015 1285);
FORCEPROP 0 LASTPIN (-8025 1225) $PN H42
J 0
(-8015 1235);
DISPLAY 0.489362 (-8015 1235);
PAINT MONO (-8015 1235);
FORCEPROP 0 LASTPIN (-8025 1175) $PN H45
J 0
(-8015 1185);
DISPLAY 0.489362 (-8015 1185);
PAINT MONO (-8015 1185);
FORCEPROP 0 LASTPIN (-8025 1125) $PN H48
J 0
(-8015 1135);
DISPLAY 0.489362 (-8015 1135);
PAINT MONO (-8015 1135);
FORCEPROP 0 LASTPIN (-8025 1075) $PN H51
J 0
(-8015 1085);
DISPLAY 0.489362 (-8015 1085);
PAINT MONO (-8015 1085);
FORCEPROP 0 LASTPIN (-8025 1025) $PN H54
J 0
(-8015 1035);
DISPLAY 0.489362 (-8015 1035);
PAINT MONO (-8015 1035);
FORCEPROP 0 LASTPIN (-8025 975) $PN H59
J 0
(-8015 985);
DISPLAY 0.489362 (-8015 985);
PAINT MONO (-8015 985);
FORCEPROP 0 LASTPIN (-8025 925) $PN H61
J 0
(-8015 935);
DISPLAY 0.489362 (-8015 935);
PAINT MONO (-8015 935);
FORCEPROP 0 LASTPIN (-8025 875) $PN H66
J 0
(-8015 885);
DISPLAY 0.489362 (-8015 885);
PAINT MONO (-8015 885);
FORCEPROP 0 LASTPIN (-8025 825) $PN H68
J 0
(-8015 835);
DISPLAY 0.489362 (-8015 835);
PAINT MONO (-8015 835);
FORCEPROP 0 LASTPIN (-8025 775) $PN H73
J 0
(-8015 785);
DISPLAY 0.489362 (-8015 785);
PAINT MONO (-8015 785);
FORCEPROP 0 LASTPIN (-8025 725) $PN J1
J 0
(-8015 735);
DISPLAY 0.489362 (-8015 735);
PAINT MONO (-8015 735);
FORCEPROP 0 LASTPIN (-8025 675) $PN J4
J 0
(-8015 685);
DISPLAY 0.489362 (-8015 685);
PAINT MONO (-8015 685);
FORCEPROP 0 LASTPIN (-8025 625) $PN J6
J 0
(-8015 635);
DISPLAY 0.489362 (-8015 635);
PAINT MONO (-8015 635);
FORCEPROP 0 LASTPIN (-8025 575) $PN J8
J 0
(-8015 585);
DISPLAY 0.489362 (-8015 585);
PAINT MONO (-8015 585);
FORCEPROP 0 LASTPIN (-8025 525) $PN J11
J 0
(-8015 535);
DISPLAY 0.489362 (-8015 535);
PAINT MONO (-8015 535);
FORCEPROP 0 LASTPIN (-8025 475) $PN J13
J 0
(-8015 485);
DISPLAY 0.489362 (-8015 485);
PAINT MONO (-8015 485);
FORCEPROP 2 LAST PART_TYPE SMLF
J 0
(-8975 6700);
DISPLAY 1.021277 (-8975 6700);
FORCEPROP 1 LAST MATERIAL IO
J 0
(-8970 6507);
DISPLAY 0.489362 (-8970 6507);
PAINT SKYBLUE (-8970 6507);
FORCEPROP 2 LAST VALUE SOCKET6096_13568-001
J 0
(-8975 6575);
DISPLAY 0.489362 (-8975 6575);
PAINT SKYBLUE (-8975 6575);
FORCEPROP 1 LAST PART_NUMBER DGA^6000030
J 0
(-8975 6650);
DISPLAY 0.489362 (-8975 6650);
PAINT SKYBLUE (-8975 6650);
FORCEPROP 2 LAST CDS_LIB pure_quanta
J 0
(-8575 3425);
DISPLAY INVISIBLE (-8575 3425);
FORCEPROP 1 LAST CDS_LMAN_SYM_OUTLINE -400,3050,400,-3050
J 0
(-8575 3425);
DISPLAY 0.468085 (-8575 3425);
PAINT GREEN (-8575 3425);
DISPLAY INVISIBLE (-8575 3425);
FORCEPROP 1 LAST NEEDS_NO_SIZE TRUE
J 0
(-8575 3425);
DISPLAY 0.723404 (-8575 3425);
PAINT GREEN (-8575 3425);
DISPLAY INVISIBLE (-8575 3425);
FORCEPROP 1 LAST PATH I1
J 0
(-8575 3425);
DISPLAY 0.723404 (-8575 3425);
PAINT GREEN (-8575 3425);
DISPLAY INVISIBLE (-8575 3425);
FORCEADD GENOA_SP5..30
(-5575 3475);
FORCEPROP 1 LAST LOCATION U26
J 0
(-5975 6650);
DISPLAY 0.489362 (-5975 6650);
PAINT SKYBLUE (-5975 6650);
FORCEPROP 0 LAST $SEC 30
J 0
(-5950 6875);
DISPLAY 0.680851 (-5950 6875);
PAINT MONO (-5950 6875);
DISPLAY INVISIBLE (-5950 6875);
FORCEPROP 0 LAST CDS_SEC 30
J 0
(-5950 6875);
DISPLAY 1.021277 (-5950 6875);
DISPLAY INVISIBLE (-5950 6875);
FORCEPROP 0 LASTPIN (-5025 5625) $PN AA1
J 0
(-5015 5635);
DISPLAY 0.489362 (-5015 5635);
PAINT MONO (-5015 5635);
FORCEPROP 0 LASTPIN (-5025 5575) $PN AA4
J 0
(-5015 5585);
DISPLAY 0.489362 (-5015 5585);
PAINT MONO (-5015 5585);
FORCEPROP 0 LASTPIN (-5025 5525) $PN AA6
J 0
(-5015 5535);
DISPLAY 0.489362 (-5015 5535);
PAINT MONO (-5015 5535);
FORCEPROP 0 LASTPIN (-5025 5475) $PN AA8
J 0
(-5015 5485);
DISPLAY 0.489362 (-5015 5485);
PAINT MONO (-5015 5485);
FORCEPROP 0 LASTPIN (-5025 5425) $PN AA11
J 0
(-5015 5435);
DISPLAY 0.489362 (-5015 5435);
PAINT MONO (-5015 5435);
FORCEPROP 0 LASTPIN (-5025 5375) $PN AA13
J 0
(-5015 5385);
DISPLAY 0.489362 (-5015 5385);
PAINT MONO (-5015 5385);
FORCEPROP 0 LASTPIN (-5025 5325) $PN AA15
J 0
(-5015 5335);
DISPLAY 0.489362 (-5015 5335);
PAINT MONO (-5015 5335);
FORCEPROP 0 LASTPIN (-5025 5275) $PN AA18
J 0
(-5015 5285);
DISPLAY 0.489362 (-5015 5285);
PAINT MONO (-5015 5285);
FORCEPROP 0 LASTPIN (-5025 5225) $PN AA20
J 0
(-5015 5235);
DISPLAY 0.489362 (-5015 5235);
PAINT MONO (-5015 5235);
FORCEPROP 0 LASTPIN (-5025 5175) $PN AA31
J 0
(-5015 5185);
DISPLAY 0.489362 (-5015 5185);
PAINT MONO (-5015 5185);
FORCEPROP 0 LASTPIN (-5025 5125) $PN AA34
J 0
(-5015 5135);
DISPLAY 0.489362 (-5015 5135);
PAINT MONO (-5015 5135);
FORCEPROP 0 LASTPIN (-5025 5075) $PN AA35
J 0
(-5015 5085);
DISPLAY 0.489362 (-5015 5085);
PAINT MONO (-5015 5085);
FORCEPROP 0 LASTPIN (-5025 5025) $PN AA36
J 0
(-5015 5035);
DISPLAY 0.489362 (-5015 5035);
PAINT MONO (-5015 5035);
FORCEPROP 0 LASTPIN (-5025 4975) $PN AA40
J 0
(-5015 4985);
DISPLAY 0.489362 (-5015 4985);
PAINT MONO (-5015 4985);
FORCEPROP 0 LASTPIN (-5025 4925) $PN AA41
J 0
(-5015 4935);
DISPLAY 0.489362 (-5015 4935);
PAINT MONO (-5015 4935);
FORCEPROP 0 LASTPIN (-5025 4875) $PN AA45
J 0
(-5015 4885);
DISPLAY 0.489362 (-5015 4885);
PAINT MONO (-5015 4885);
FORCEPROP 0 LASTPIN (-5025 4825) $PN AA56
J 0
(-5015 4835);
DISPLAY 0.489362 (-5015 4835);
PAINT MONO (-5015 4835);
FORCEPROP 0 LASTPIN (-5025 4775) $PN AA58
J 0
(-5015 4785);
DISPLAY 0.489362 (-5015 4785);
PAINT MONO (-5015 4785);
FORCEPROP 0 LASTPIN (-5025 4725) $PN AA61
J 0
(-5015 4735);
DISPLAY 0.489362 (-5015 4735);
PAINT MONO (-5015 4735);
FORCEPROP 0 LASTPIN (-5025 4675) $PN AA63
J 0
(-5015 4685);
DISPLAY 0.489362 (-5015 4685);
PAINT MONO (-5015 4685);
FORCEPROP 0 LASTPIN (-5025 4625) $PN AA65
J 0
(-5015 4635);
DISPLAY 0.489362 (-5015 4635);
PAINT MONO (-5015 4635);
FORCEPROP 0 LASTPIN (-5025 4575) $PN AA68
J 0
(-5015 4585);
DISPLAY 0.489362 (-5015 4585);
PAINT MONO (-5015 4585);
FORCEPROP 0 LASTPIN (-5025 4525) $PN AA70
J 0
(-5015 4535);
DISPLAY 0.489362 (-5015 4535);
PAINT MONO (-5015 4535);
FORCEPROP 0 LASTPIN (-5025 4475) $PN AA75
J 0
(-5015 4485);
DISPLAY 0.489362 (-5015 4485);
PAINT MONO (-5015 4485);
FORCEPROP 0 LASTPIN (-5025 4425) $PN AB3
J 0
(-5015 4435);
DISPLAY 0.489362 (-5015 4435);
PAINT MONO (-5015 4435);
FORCEPROP 0 LASTPIN (-5025 4375) $PN AB5
J 0
(-5015 4385);
DISPLAY 0.489362 (-5015 4385);
PAINT MONO (-5015 4385);
FORCEPROP 0 LASTPIN (-5025 4325) $PN AB8
J 0
(-5015 4335);
DISPLAY 0.489362 (-5015 4335);
PAINT MONO (-5015 4335);
FORCEPROP 0 LASTPIN (-5025 4275) $PN AB10
J 0
(-5015 4285);
DISPLAY 0.489362 (-5015 4285);
PAINT MONO (-5015 4285);
FORCEPROP 0 LASTPIN (-5025 4225) $PN AB12
J 0
(-5015 4235);
DISPLAY 0.489362 (-5015 4235);
PAINT MONO (-5015 4235);
FORCEPROP 0 LASTPIN (-5025 4175) $PN AB15
J 0
(-5015 4185);
DISPLAY 0.489362 (-5015 4185);
PAINT MONO (-5015 4185);
FORCEPROP 0 LASTPIN (-5025 4125) $PN AB17
J 0
(-5015 4135);
DISPLAY 0.489362 (-5015 4135);
PAINT MONO (-5015 4135);
FORCEPROP 0 LASTPIN (-5025 4075) $PN AB19
J 0
(-5015 4085);
DISPLAY 0.489362 (-5015 4085);
PAINT MONO (-5015 4085);
FORCEPROP 0 LASTPIN (-5025 4025) $PN AB22
J 0
(-5015 4035);
DISPLAY 0.489362 (-5015 4035);
PAINT MONO (-5015 4035);
FORCEPROP 0 LASTPIN (-5025 3975) $PN AB25
J 0
(-5015 3985);
DISPLAY 0.489362 (-5015 3985);
PAINT MONO (-5015 3985);
FORCEPROP 0 LASTPIN (-5025 3925) $PN AB28
J 0
(-5015 3935);
DISPLAY 0.489362 (-5015 3935);
PAINT MONO (-5015 3935);
FORCEPROP 0 LASTPIN (-5025 3875) $PN AB31
J 0
(-5015 3885);
DISPLAY 0.489362 (-5015 3885);
PAINT MONO (-5015 3885);
FORCEPROP 0 LASTPIN (-5025 3825) $PN AB34
J 0
(-5015 3835);
DISPLAY 0.489362 (-5015 3835);
PAINT MONO (-5015 3835);
FORCEPROP 0 LASTPIN (-5025 3775) $PN AB37
J 0
(-5015 3785);
DISPLAY 0.489362 (-5015 3785);
PAINT MONO (-5015 3785);
FORCEPROP 0 LASTPIN (-5025 3725) $PN AB39
J 0
(-5015 3735);
DISPLAY 0.489362 (-5015 3735);
PAINT MONO (-5015 3735);
FORCEPROP 0 LASTPIN (-5025 3675) $PN AB42
J 0
(-5015 3685);
DISPLAY 0.489362 (-5015 3685);
PAINT MONO (-5015 3685);
FORCEPROP 0 LASTPIN (-5025 3625) $PN AB45
J 0
(-5015 3635);
DISPLAY 0.489362 (-5015 3635);
PAINT MONO (-5015 3635);
FORCEPROP 0 LASTPIN (-5025 3575) $PN AB48
J 0
(-5015 3585);
DISPLAY 0.489362 (-5015 3585);
PAINT MONO (-5015 3585);
FORCEPROP 0 LASTPIN (-5025 3525) $PN AB51
J 0
(-5015 3535);
DISPLAY 0.489362 (-5015 3535);
PAINT MONO (-5015 3535);
FORCEPROP 0 LASTPIN (-5025 3475) $PN AB54
J 0
(-5015 3485);
DISPLAY 0.489362 (-5015 3485);
PAINT MONO (-5015 3485);
FORCEPROP 0 LASTPIN (-5025 3425) $PN AB57
J 0
(-5015 3435);
DISPLAY 0.489362 (-5015 3435);
PAINT MONO (-5015 3435);
FORCEPROP 0 LASTPIN (-5025 3375) $PN AB59
J 0
(-5015 3385);
DISPLAY 0.489362 (-5015 3385);
PAINT MONO (-5015 3385);
FORCEPROP 0 LASTPIN (-5025 3325) $PN AB61
J 0
(-5015 3335);
DISPLAY 0.489362 (-5015 3335);
PAINT MONO (-5015 3335);
FORCEPROP 0 LASTPIN (-5025 3275) $PN AB64
J 0
(-5015 3285);
DISPLAY 0.489362 (-5015 3285);
PAINT MONO (-5015 3285);
FORCEPROP 0 LASTPIN (-5025 3225) $PN AB66
J 0
(-5015 3235);
DISPLAY 0.489362 (-5015 3235);
PAINT MONO (-5015 3235);
FORCEPROP 0 LASTPIN (-5025 3175) $PN AB68
J 0
(-5015 3185);
DISPLAY 0.489362 (-5015 3185);
PAINT MONO (-5015 3185);
FORCEPROP 0 LASTPIN (-5025 3125) $PN AB71
J 0
(-5015 3135);
DISPLAY 0.489362 (-5015 3135);
PAINT MONO (-5015 3135);
FORCEPROP 0 LASTPIN (-5025 3075) $PN AB73
J 0
(-5015 3085);
DISPLAY 0.489362 (-5015 3085);
PAINT MONO (-5015 3085);
FORCEPROP 0 LASTPIN (-5025 3025) $PN AC1
J 0
(-5015 3035);
DISPLAY 0.489362 (-5015 3035);
PAINT MONO (-5015 3035);
FORCEPROP 0 LASTPIN (-5025 2975) $PN AC6
J 0
(-5015 2985);
DISPLAY 0.489362 (-5015 2985);
PAINT MONO (-5015 2985);
FORCEPROP 0 LASTPIN (-5025 2925) $PN AC8
J 0
(-5015 2935);
DISPLAY 0.489362 (-5015 2935);
PAINT MONO (-5015 2935);
FORCEPROP 0 LASTPIN (-5025 2875) $PN AC13
J 0
(-5015 2885);
DISPLAY 0.489362 (-5015 2885);
PAINT MONO (-5015 2885);
FORCEPROP 0 LASTPIN (-5025 2825) $PN AC15
J 0
(-5015 2835);
DISPLAY 0.489362 (-5015 2835);
PAINT MONO (-5015 2835);
FORCEPROP 0 LASTPIN (-5025 2775) $PN AC20
J 0
(-5015 2785);
DISPLAY 0.489362 (-5015 2785);
PAINT MONO (-5015 2785);
FORCEPROP 0 LASTPIN (-5025 2725) $PN AC22
J 0
(-5015 2735);
DISPLAY 0.489362 (-5015 2735);
PAINT MONO (-5015 2735);
FORCEPROP 0 LASTPIN (-5025 2675) $PN AC25
J 0
(-5015 2685);
DISPLAY 0.489362 (-5015 2685);
PAINT MONO (-5015 2685);
FORCEPROP 0 LASTPIN (-5025 2625) $PN AC28
J 0
(-5015 2635);
DISPLAY 0.489362 (-5015 2635);
PAINT MONO (-5015 2635);
FORCEPROP 0 LASTPIN (-5025 2575) $PN AC31
J 0
(-5015 2585);
DISPLAY 0.489362 (-5015 2585);
PAINT MONO (-5015 2585);
FORCEPROP 0 LASTPIN (-5025 2525) $PN AC34
J 0
(-5015 2535);
DISPLAY 0.489362 (-5015 2535);
PAINT MONO (-5015 2535);
FORCEPROP 0 LASTPIN (-5025 2475) $PN AC42
J 0
(-5015 2485);
DISPLAY 0.489362 (-5015 2485);
PAINT MONO (-5015 2485);
FORCEPROP 0 LASTPIN (-5025 2425) $PN AC45
J 0
(-5015 2435);
DISPLAY 0.489362 (-5015 2435);
PAINT MONO (-5015 2435);
FORCEPROP 0 LASTPIN (-5025 2375) $PN AC48
J 0
(-5015 2385);
DISPLAY 0.489362 (-5015 2385);
PAINT MONO (-5015 2385);
FORCEPROP 0 LASTPIN (-5025 2325) $PN AC51
J 0
(-5015 2335);
DISPLAY 0.489362 (-5015 2335);
PAINT MONO (-5015 2335);
FORCEPROP 0 LASTPIN (-5025 2275) $PN AC54
J 0
(-5015 2285);
DISPLAY 0.489362 (-5015 2285);
PAINT MONO (-5015 2285);
FORCEPROP 0 LASTPIN (-5025 2225) $PN AC56
J 0
(-5015 2235);
DISPLAY 0.489362 (-5015 2235);
PAINT MONO (-5015 2235);
FORCEPROP 0 LASTPIN (-5025 2175) $PN AC61
J 0
(-5015 2185);
DISPLAY 0.489362 (-5015 2185);
PAINT MONO (-5015 2185);
FORCEPROP 0 LASTPIN (-5025 2125) $PN AC63
J 0
(-5015 2135);
DISPLAY 0.489362 (-5015 2135);
PAINT MONO (-5015 2135);
FORCEPROP 0 LASTPIN (-5025 2075) $PN AC68
J 0
(-5015 2085);
DISPLAY 0.489362 (-5015 2085);
PAINT MONO (-5015 2085);
FORCEPROP 0 LASTPIN (-5025 2025) $PN AC70
J 0
(-5015 2035);
DISPLAY 0.489362 (-5015 2035);
PAINT MONO (-5015 2035);
FORCEPROP 0 LASTPIN (-5025 1975) $PN AC75
J 0
(-5015 1985);
DISPLAY 0.489362 (-5015 1985);
PAINT MONO (-5015 1985);
FORCEPROP 0 LASTPIN (-5025 1925) $PN AD3
J 0
(-5015 1935);
DISPLAY 0.489362 (-5015 1935);
PAINT MONO (-5015 1935);
FORCEPROP 0 LASTPIN (-5025 1875) $PN AD5
J 0
(-5015 1885);
DISPLAY 0.489362 (-5015 1885);
PAINT MONO (-5015 1885);
FORCEPROP 0 LASTPIN (-5025 1825) $PN AD8
J 0
(-5015 1835);
DISPLAY 0.489362 (-5015 1835);
PAINT MONO (-5015 1835);
FORCEPROP 0 LASTPIN (-5025 1775) $PN AD10
J 0
(-5015 1785);
DISPLAY 0.489362 (-5015 1785);
PAINT MONO (-5015 1785);
FORCEPROP 0 LASTPIN (-5025 1725) $PN AD12
J 0
(-5015 1735);
DISPLAY 0.489362 (-5015 1735);
PAINT MONO (-5015 1735);
FORCEPROP 0 LASTPIN (-5025 1675) $PN AD15
J 0
(-5015 1685);
DISPLAY 0.489362 (-5015 1685);
PAINT MONO (-5015 1685);
FORCEPROP 0 LASTPIN (-5025 1625) $PN AD17
J 0
(-5015 1635);
DISPLAY 0.489362 (-5015 1635);
PAINT MONO (-5015 1635);
FORCEPROP 0 LASTPIN (-5025 1575) $PN AD19
J 0
(-5015 1585);
DISPLAY 0.489362 (-5015 1585);
PAINT MONO (-5015 1585);
FORCEPROP 0 LASTPIN (-5025 1525) $PN AD23
J 0
(-5015 1535);
DISPLAY 0.489362 (-5015 1535);
PAINT MONO (-5015 1535);
FORCEPROP 0 LASTPIN (-5025 1475) $PN AD24
J 0
(-5015 1485);
DISPLAY 0.489362 (-5015 1485);
PAINT MONO (-5015 1485);
FORCEPROP 0 LASTPIN (-5025 1425) $PN AD25
J 0
(-5015 1435);
DISPLAY 0.489362 (-5015 1435);
PAINT MONO (-5015 1435);
FORCEPROP 0 LASTPIN (-5025 1375) $PN AD26
J 0
(-5015 1385);
DISPLAY 0.489362 (-5015 1385);
PAINT MONO (-5015 1385);
FORCEPROP 0 LASTPIN (-5025 1325) $PN AD27
J 0
(-5015 1335);
DISPLAY 0.489362 (-5015 1335);
PAINT MONO (-5015 1335);
FORCEPROP 0 LASTPIN (-5025 1275) $PN AD28
J 0
(-5015 1285);
DISPLAY 0.489362 (-5015 1285);
PAINT MONO (-5015 1285);
FORCEPROP 0 LASTPIN (-5025 1225) $PN AD29
J 0
(-5015 1235);
DISPLAY 0.489362 (-5015 1235);
PAINT MONO (-5015 1235);
FORCEPROP 0 LASTPIN (-5025 1175) $PN AD30
J 0
(-5015 1185);
DISPLAY 0.489362 (-5015 1185);
PAINT MONO (-5015 1185);
FORCEPROP 0 LASTPIN (-5025 1125) $PN AD32
J 0
(-5015 1135);
DISPLAY 0.489362 (-5015 1135);
PAINT MONO (-5015 1135);
FORCEPROP 0 LASTPIN (-5025 1075) $PN AD33
J 0
(-5015 1085);
DISPLAY 0.489362 (-5015 1085);
PAINT MONO (-5015 1085);
FORCEPROP 0 LASTPIN (-5025 1025) $PN AD34
J 0
(-5015 1035);
DISPLAY 0.489362 (-5015 1035);
PAINT MONO (-5015 1035);
FORCEPROP 0 LASTPIN (-5025 975) $PN AD37
J 0
(-5015 985);
DISPLAY 0.489362 (-5015 985);
PAINT MONO (-5015 985);
FORCEPROP 0 LASTPIN (-5025 925) $PN AD39
J 0
(-5015 935);
DISPLAY 0.489362 (-5015 935);
PAINT MONO (-5015 935);
FORCEPROP 0 LASTPIN (-5025 875) $PN AD42
J 0
(-5015 885);
DISPLAY 0.489362 (-5015 885);
PAINT MONO (-5015 885);
FORCEPROP 0 LASTPIN (-5025 825) $PN AD43
J 0
(-5015 835);
DISPLAY 0.489362 (-5015 835);
PAINT MONO (-5015 835);
FORCEPROP 0 LASTPIN (-5025 775) $PN AD44
J 0
(-5015 785);
DISPLAY 0.489362 (-5015 785);
PAINT MONO (-5015 785);
FORCEPROP 0 LASTPIN (-5025 725) $PN AD45
J 0
(-5015 735);
DISPLAY 0.489362 (-5015 735);
PAINT MONO (-5015 735);
FORCEPROP 0 LASTPIN (-5025 675) $PN AD46
J 0
(-5015 685);
DISPLAY 0.489362 (-5015 685);
PAINT MONO (-5015 685);
FORCEPROP 0 LASTPIN (-5025 625) $PN AD47
J 0
(-5015 635);
DISPLAY 0.489362 (-5015 635);
PAINT MONO (-5015 635);
FORCEPROP 0 LASTPIN (-5025 575) $PN AD48
J 0
(-5015 585);
DISPLAY 0.489362 (-5015 585);
PAINT MONO (-5015 585);
FORCEPROP 0 LASTPIN (-6125 6325) $PN T66
J 2
(-6135 6335);
DISPLAY 0.489362 (-6135 6335);
PAINT MONO (-6135 6335);
FORCEPROP 0 LASTPIN (-6125 6275) $PN T68
J 2
(-6135 6285);
DISPLAY 0.489362 (-6135 6285);
PAINT MONO (-6135 6285);
FORCEPROP 0 LASTPIN (-6125 6225) $PN T71
J 2
(-6135 6235);
DISPLAY 0.489362 (-6135 6235);
PAINT MONO (-6135 6235);
FORCEPROP 0 LASTPIN (-6125 6175) $PN T73
J 2
(-6135 6185);
DISPLAY 0.489362 (-6135 6185);
PAINT MONO (-6135 6185);
FORCEPROP 0 LASTPIN (-6125 6125) $PN U1
J 2
(-6135 6135);
DISPLAY 0.489362 (-6135 6135);
PAINT MONO (-6135 6135);
FORCEPROP 0 LASTPIN (-6125 6075) $PN U6
J 2
(-6135 6085);
DISPLAY 0.489362 (-6135 6085);
PAINT MONO (-6135 6085);
FORCEPROP 0 LASTPIN (-6125 6025) $PN U8
J 2
(-6135 6035);
DISPLAY 0.489362 (-6135 6035);
PAINT MONO (-6135 6035);
FORCEPROP 0 LASTPIN (-6125 5975) $PN U13
J 2
(-6135 5985);
DISPLAY 0.489362 (-6135 5985);
PAINT MONO (-6135 5985);
FORCEPROP 0 LASTPIN (-6125 5925) $PN U15
J 2
(-6135 5935);
DISPLAY 0.489362 (-6135 5935);
PAINT MONO (-6135 5935);
FORCEPROP 0 LASTPIN (-6125 5875) $PN U20
J 2
(-6135 5885);
DISPLAY 0.489362 (-6135 5885);
PAINT MONO (-6135 5885);
FORCEPROP 0 LASTPIN (-6125 5825) $PN U22
J 2
(-6135 5835);
DISPLAY 0.489362 (-6135 5835);
PAINT MONO (-6135 5835);
FORCEPROP 0 LASTPIN (-6125 5775) $PN U25
J 2
(-6135 5785);
DISPLAY 0.489362 (-6135 5785);
PAINT MONO (-6135 5785);
FORCEPROP 0 LASTPIN (-6125 5725) $PN U28
J 2
(-6135 5735);
DISPLAY 0.489362 (-6135 5735);
PAINT MONO (-6135 5735);
FORCEPROP 0 LASTPIN (-6125 5675) $PN U31
J 2
(-6135 5685);
DISPLAY 0.489362 (-6135 5685);
PAINT MONO (-6135 5685);
FORCEPROP 0 LASTPIN (-6125 5625) $PN U34
J 2
(-6135 5635);
DISPLAY 0.489362 (-6135 5635);
PAINT MONO (-6135 5635);
FORCEPROP 0 LASTPIN (-6125 5575) $PN U42
J 2
(-6135 5585);
DISPLAY 0.489362 (-6135 5585);
PAINT MONO (-6135 5585);
FORCEPROP 0 LASTPIN (-6125 5525) $PN U45
J 2
(-6135 5535);
DISPLAY 0.489362 (-6135 5535);
PAINT MONO (-6135 5535);
FORCEPROP 0 LASTPIN (-6125 5475) $PN U48
J 2
(-6135 5485);
DISPLAY 0.489362 (-6135 5485);
PAINT MONO (-6135 5485);
FORCEPROP 0 LASTPIN (-6125 5425) $PN U51
J 2
(-6135 5435);
DISPLAY 0.489362 (-6135 5435);
PAINT MONO (-6135 5435);
FORCEPROP 0 LASTPIN (-6125 5375) $PN U54
J 2
(-6135 5385);
DISPLAY 0.489362 (-6135 5385);
PAINT MONO (-6135 5385);
FORCEPROP 0 LASTPIN (-6125 5325) $PN U56
J 2
(-6135 5335);
DISPLAY 0.489362 (-6135 5335);
PAINT MONO (-6135 5335);
FORCEPROP 0 LASTPIN (-6125 5275) $PN U61
J 2
(-6135 5285);
DISPLAY 0.489362 (-6135 5285);
PAINT MONO (-6135 5285);
FORCEPROP 0 LASTPIN (-6125 5225) $PN U63
J 2
(-6135 5235);
DISPLAY 0.489362 (-6135 5235);
PAINT MONO (-6135 5235);
FORCEPROP 0 LASTPIN (-6125 5175) $PN U68
J 2
(-6135 5185);
DISPLAY 0.489362 (-6135 5185);
PAINT MONO (-6135 5185);
FORCEPROP 0 LASTPIN (-6125 5125) $PN U70
J 2
(-6135 5135);
DISPLAY 0.489362 (-6135 5135);
PAINT MONO (-6135 5135);
FORCEPROP 0 LASTPIN (-6125 5075) $PN U75
J 2
(-6135 5085);
DISPLAY 0.489362 (-6135 5085);
PAINT MONO (-6135 5085);
FORCEPROP 0 LASTPIN (-6125 5025) $PN V3
J 2
(-6135 5035);
DISPLAY 0.489362 (-6135 5035);
PAINT MONO (-6135 5035);
FORCEPROP 0 LASTPIN (-6125 4975) $PN V5
J 2
(-6135 4985);
DISPLAY 0.489362 (-6135 4985);
PAINT MONO (-6135 4985);
FORCEPROP 0 LASTPIN (-6125 4925) $PN V8
J 2
(-6135 4935);
DISPLAY 0.489362 (-6135 4935);
PAINT MONO (-6135 4935);
FORCEPROP 0 LASTPIN (-6125 4875) $PN V10
J 2
(-6135 4885);
DISPLAY 0.489362 (-6135 4885);
PAINT MONO (-6135 4885);
FORCEPROP 0 LASTPIN (-6125 4825) $PN V12
J 2
(-6135 4835);
DISPLAY 0.489362 (-6135 4835);
PAINT MONO (-6135 4835);
FORCEPROP 0 LASTPIN (-6125 4775) $PN V15
J 2
(-6135 4785);
DISPLAY 0.489362 (-6135 4785);
PAINT MONO (-6135 4785);
FORCEPROP 0 LASTPIN (-6125 4725) $PN V17
J 2
(-6135 4735);
DISPLAY 0.489362 (-6135 4735);
PAINT MONO (-6135 4735);
FORCEPROP 0 LASTPIN (-6125 4675) $PN V19
J 2
(-6135 4685);
DISPLAY 0.489362 (-6135 4685);
PAINT MONO (-6135 4685);
FORCEPROP 0 LASTPIN (-6125 4625) $PN V23
J 2
(-6135 4635);
DISPLAY 0.489362 (-6135 4635);
PAINT MONO (-6135 4635);
FORCEPROP 0 LASTPIN (-6125 4575) $PN V24
J 2
(-6135 4585);
DISPLAY 0.489362 (-6135 4585);
PAINT MONO (-6135 4585);
FORCEPROP 0 LASTPIN (-6125 4525) $PN V25
J 2
(-6135 4535);
DISPLAY 0.489362 (-6135 4535);
PAINT MONO (-6135 4535);
FORCEPROP 0 LASTPIN (-6125 4475) $PN V26
J 2
(-6135 4485);
DISPLAY 0.489362 (-6135 4485);
PAINT MONO (-6135 4485);
FORCEPROP 0 LASTPIN (-6125 4425) $PN V28
J 2
(-6135 4435);
DISPLAY 0.489362 (-6135 4435);
PAINT MONO (-6135 4435);
FORCEPROP 0 LASTPIN (-6125 4375) $PN V29
J 2
(-6135 4385);
DISPLAY 0.489362 (-6135 4385);
PAINT MONO (-6135 4385);
FORCEPROP 0 LASTPIN (-6125 4325) $PN V30
J 2
(-6135 4335);
DISPLAY 0.489362 (-6135 4335);
PAINT MONO (-6135 4335);
FORCEPROP 0 LASTPIN (-6125 4275) $PN V31
J 2
(-6135 4285);
DISPLAY 0.489362 (-6135 4285);
PAINT MONO (-6135 4285);
FORCEPROP 0 LASTPIN (-6125 4225) $PN V32
J 2
(-6135 4235);
DISPLAY 0.489362 (-6135 4235);
PAINT MONO (-6135 4235);
FORCEPROP 0 LASTPIN (-6125 4175) $PN V33
J 2
(-6135 4185);
DISPLAY 0.489362 (-6135 4185);
PAINT MONO (-6135 4185);
FORCEPROP 0 LASTPIN (-6125 4125) $PN V34
J 2
(-6135 4135);
DISPLAY 0.489362 (-6135 4135);
PAINT MONO (-6135 4135);
FORCEPROP 0 LASTPIN (-6125 4075) $PN V37
J 2
(-6135 4085);
DISPLAY 0.489362 (-6135 4085);
PAINT MONO (-6135 4085);
FORCEPROP 0 LASTPIN (-6125 4025) $PN V39
J 2
(-6135 4035);
DISPLAY 0.489362 (-6135 4035);
PAINT MONO (-6135 4035);
FORCEPROP 0 LASTPIN (-6125 3975) $PN V42
J 2
(-6135 3985);
DISPLAY 0.489362 (-6135 3985);
PAINT MONO (-6135 3985);
FORCEPROP 0 LASTPIN (-6125 3925) $PN V43
J 2
(-6135 3935);
DISPLAY 0.489362 (-6135 3935);
PAINT MONO (-6135 3935);
FORCEPROP 0 LASTPIN (-6125 3875) $PN V44
J 2
(-6135 3885);
DISPLAY 0.489362 (-6135 3885);
PAINT MONO (-6135 3885);
FORCEPROP 0 LASTPIN (-6125 3825) $PN V45
J 2
(-6135 3835);
DISPLAY 0.489362 (-6135 3835);
PAINT MONO (-6135 3835);
FORCEPROP 0 LASTPIN (-6125 3775) $PN V46
J 2
(-6135 3785);
DISPLAY 0.489362 (-6135 3785);
PAINT MONO (-6135 3785);
FORCEPROP 0 LASTPIN (-6125 3725) $PN V47
J 2
(-6135 3735);
DISPLAY 0.489362 (-6135 3735);
PAINT MONO (-6135 3735);
FORCEPROP 0 LASTPIN (-6125 3675) $PN V48
J 2
(-6135 3685);
DISPLAY 0.489362 (-6135 3685);
PAINT MONO (-6135 3685);
FORCEPROP 0 LASTPIN (-6125 3625) $PN V49
J 2
(-6135 3635);
DISPLAY 0.489362 (-6135 3635);
PAINT MONO (-6135 3635);
FORCEPROP 0 LASTPIN (-6125 3575) $PN V50
J 2
(-6135 3585);
DISPLAY 0.489362 (-6135 3585);
PAINT MONO (-6135 3585);
FORCEPROP 0 LASTPIN (-6125 3525) $PN V51
J 2
(-6135 3535);
DISPLAY 0.489362 (-6135 3535);
PAINT MONO (-6135 3535);
FORCEPROP 0 LASTPIN (-6125 3475) $PN V52
J 2
(-6135 3485);
DISPLAY 0.489362 (-6135 3485);
PAINT MONO (-6135 3485);
FORCEPROP 0 LASTPIN (-6125 3425) $PN V53
J 2
(-6135 3435);
DISPLAY 0.489362 (-6135 3435);
PAINT MONO (-6135 3435);
FORCEPROP 0 LASTPIN (-6125 3375) $PN V57
J 2
(-6135 3385);
DISPLAY 0.489362 (-6135 3385);
PAINT MONO (-6135 3385);
FORCEPROP 0 LASTPIN (-6125 3325) $PN V59
J 2
(-6135 3335);
DISPLAY 0.489362 (-6135 3335);
PAINT MONO (-6135 3335);
FORCEPROP 0 LASTPIN (-6125 3275) $PN V61
J 2
(-6135 3285);
DISPLAY 0.489362 (-6135 3285);
PAINT MONO (-6135 3285);
FORCEPROP 0 LASTPIN (-6125 3225) $PN V64
J 2
(-6135 3235);
DISPLAY 0.489362 (-6135 3235);
PAINT MONO (-6135 3235);
FORCEPROP 0 LASTPIN (-6125 3175) $PN V66
J 2
(-6135 3185);
DISPLAY 0.489362 (-6135 3185);
PAINT MONO (-6135 3185);
FORCEPROP 0 LASTPIN (-6125 3125) $PN V71
J 2
(-6135 3135);
DISPLAY 0.489362 (-6135 3135);
PAINT MONO (-6135 3135);
FORCEPROP 0 LASTPIN (-6125 3075) $PN V73
J 2
(-6135 3085);
DISPLAY 0.489362 (-6135 3085);
PAINT MONO (-6135 3085);
FORCEPROP 0 LASTPIN (-6125 3025) $PN W1
J 2
(-6135 3035);
DISPLAY 0.489362 (-6135 3035);
PAINT MONO (-6135 3035);
FORCEPROP 0 LASTPIN (-6125 2975) $PN W4
J 2
(-6135 2985);
DISPLAY 0.489362 (-6135 2985);
PAINT MONO (-6135 2985);
FORCEPROP 0 LASTPIN (-6125 2925) $PN W6
J 2
(-6135 2935);
DISPLAY 0.489362 (-6135 2935);
PAINT MONO (-6135 2935);
FORCEPROP 0 LASTPIN (-6125 2875) $PN W8
J 2
(-6135 2885);
DISPLAY 0.489362 (-6135 2885);
PAINT MONO (-6135 2885);
FORCEPROP 0 LASTPIN (-6125 2825) $PN W11
J 2
(-6135 2835);
DISPLAY 0.489362 (-6135 2835);
PAINT MONO (-6135 2835);
FORCEPROP 0 LASTPIN (-6125 2775) $PN W13
J 2
(-6135 2785);
DISPLAY 0.489362 (-6135 2785);
PAINT MONO (-6135 2785);
FORCEPROP 0 LASTPIN (-6125 2725) $PN W15
J 2
(-6135 2735);
DISPLAY 0.489362 (-6135 2735);
PAINT MONO (-6135 2735);
FORCEPROP 0 LASTPIN (-6125 2675) $PN W18
J 2
(-6135 2685);
DISPLAY 0.489362 (-6135 2685);
PAINT MONO (-6135 2685);
FORCEPROP 0 LASTPIN (-6125 2625) $PN W20
J 2
(-6135 2635);
DISPLAY 0.489362 (-6135 2635);
PAINT MONO (-6135 2635);
FORCEPROP 0 LASTPIN (-6125 2575) $PN W22
J 2
(-6135 2585);
DISPLAY 0.489362 (-6135 2585);
PAINT MONO (-6135 2585);
FORCEPROP 0 LASTPIN (-6125 2525) $PN W25
J 2
(-6135 2535);
DISPLAY 0.489362 (-6135 2535);
PAINT MONO (-6135 2535);
FORCEPROP 0 LASTPIN (-6125 2475) $PN W28
J 2
(-6135 2485);
DISPLAY 0.489362 (-6135 2485);
PAINT MONO (-6135 2485);
FORCEPROP 0 LASTPIN (-6125 2425) $PN W34
J 2
(-6135 2435);
DISPLAY 0.489362 (-6135 2435);
PAINT MONO (-6135 2435);
FORCEPROP 0 LASTPIN (-6125 2375) $PN W35
J 2
(-6135 2385);
DISPLAY 0.489362 (-6135 2385);
PAINT MONO (-6135 2385);
FORCEPROP 0 LASTPIN (-6125 2325) $PN W36
J 2
(-6135 2335);
DISPLAY 0.489362 (-6135 2335);
PAINT MONO (-6135 2335);
FORCEPROP 0 LASTPIN (-6125 2275) $PN W40
J 2
(-6135 2285);
DISPLAY 0.489362 (-6135 2285);
PAINT MONO (-6135 2285);
FORCEPROP 0 LASTPIN (-6125 2225) $PN W41
J 2
(-6135 2235);
DISPLAY 0.489362 (-6135 2235);
PAINT MONO (-6135 2235);
FORCEPROP 0 LASTPIN (-6125 2175) $PN W42
J 2
(-6135 2185);
DISPLAY 0.489362 (-6135 2185);
PAINT MONO (-6135 2185);
FORCEPROP 0 LASTPIN (-6125 2125) $PN W45
J 2
(-6135 2135);
DISPLAY 0.489362 (-6135 2135);
PAINT MONO (-6135 2135);
FORCEPROP 0 LASTPIN (-6125 2075) $PN W48
J 2
(-6135 2085);
DISPLAY 0.489362 (-6135 2085);
PAINT MONO (-6135 2085);
FORCEPROP 0 LASTPIN (-6125 2025) $PN W51
J 2
(-6135 2035);
DISPLAY 0.489362 (-6135 2035);
PAINT MONO (-6135 2035);
FORCEPROP 0 LASTPIN (-6125 1975) $PN W54
J 2
(-6135 1985);
DISPLAY 0.489362 (-6135 1985);
PAINT MONO (-6135 1985);
FORCEPROP 0 LASTPIN (-6125 1925) $PN W56
J 2
(-6135 1935);
DISPLAY 0.489362 (-6135 1935);
PAINT MONO (-6135 1935);
FORCEPROP 0 LASTPIN (-6125 1875) $PN W58
J 2
(-6135 1885);
DISPLAY 0.489362 (-6135 1885);
PAINT MONO (-6135 1885);
FORCEPROP 0 LASTPIN (-6125 1825) $PN W61
J 2
(-6135 1835);
DISPLAY 0.489362 (-6135 1835);
PAINT MONO (-6135 1835);
FORCEPROP 0 LASTPIN (-6125 1775) $PN W63
J 2
(-6135 1785);
DISPLAY 0.489362 (-6135 1785);
PAINT MONO (-6135 1785);
FORCEPROP 0 LASTPIN (-6125 1725) $PN W65
J 2
(-6135 1735);
DISPLAY 0.489362 (-6135 1735);
PAINT MONO (-6135 1735);
FORCEPROP 0 LASTPIN (-6125 1675) $PN W68
J 2
(-6135 1685);
DISPLAY 0.489362 (-6135 1685);
PAINT MONO (-6135 1685);
FORCEPROP 0 LASTPIN (-6125 1625) $PN W70
J 2
(-6135 1635);
DISPLAY 0.489362 (-6135 1635);
PAINT MONO (-6135 1635);
FORCEPROP 0 LASTPIN (-6125 1575) $PN W72
J 2
(-6135 1585);
DISPLAY 0.489362 (-6135 1585);
PAINT MONO (-6135 1585);
FORCEPROP 0 LASTPIN (-6125 1525) $PN W75
J 2
(-6135 1535);
DISPLAY 0.489362 (-6135 1535);
PAINT MONO (-6135 1535);
FORCEPROP 0 LASTPIN (-6125 1475) $PN Y3
J 2
(-6135 1485);
DISPLAY 0.489362 (-6135 1485);
PAINT MONO (-6135 1485);
FORCEPROP 0 LASTPIN (-6125 1425) $PN Y8
J 2
(-6135 1435);
DISPLAY 0.489362 (-6135 1435);
PAINT MONO (-6135 1435);
FORCEPROP 0 LASTPIN (-6125 1375) $PN Y10
J 2
(-6135 1385);
DISPLAY 0.489362 (-6135 1385);
PAINT MONO (-6135 1385);
FORCEPROP 0 LASTPIN (-6125 1325) $PN Y15
J 2
(-6135 1335);
DISPLAY 0.489362 (-6135 1335);
PAINT MONO (-6135 1335);
FORCEPROP 0 LASTPIN (-6125 1275) $PN Y17
J 2
(-6135 1285);
DISPLAY 0.489362 (-6135 1285);
PAINT MONO (-6135 1285);
FORCEPROP 0 LASTPIN (-6125 1225) $PN Y22
J 2
(-6135 1235);
DISPLAY 0.489362 (-6135 1235);
PAINT MONO (-6135 1235);
FORCEPROP 0 LASTPIN (-6125 1175) $PN Y23
J 2
(-6135 1185);
DISPLAY 0.489362 (-6135 1185);
PAINT MONO (-6135 1185);
FORCEPROP 0 LASTPIN (-6125 1125) $PN Y24
J 2
(-6135 1135);
DISPLAY 0.489362 (-6135 1135);
PAINT MONO (-6135 1135);
FORCEPROP 0 LASTPIN (-6125 1075) $PN Y25
J 2
(-6135 1085);
DISPLAY 0.489362 (-6135 1085);
PAINT MONO (-6135 1085);
FORCEPROP 0 LASTPIN (-6125 1025) $PN Y26
J 2
(-6135 1035);
DISPLAY 0.489362 (-6135 1035);
PAINT MONO (-6135 1035);
FORCEPROP 0 LASTPIN (-6125 975) $PN Y27
J 2
(-6135 985);
DISPLAY 0.489362 (-6135 985);
PAINT MONO (-6135 985);
FORCEPROP 0 LASTPIN (-6125 925) $PN Y28
J 2
(-6135 935);
DISPLAY 0.489362 (-6135 935);
PAINT MONO (-6135 935);
FORCEPROP 0 LASTPIN (-6125 875) $PN Y31
J 2
(-6135 885);
DISPLAY 0.489362 (-6135 885);
PAINT MONO (-6135 885);
FORCEPROP 0 LASTPIN (-6125 825) $PN Y32
J 2
(-6135 835);
DISPLAY 0.489362 (-6135 835);
PAINT MONO (-6135 835);
FORCEPROP 0 LASTPIN (-6125 775) $PN Y33
J 2
(-6135 785);
DISPLAY 0.489362 (-6135 785);
PAINT MONO (-6135 785);
FORCEPROP 0 LASTPIN (-6125 725) $PN Y34
J 2
(-6135 735);
DISPLAY 0.489362 (-6135 735);
PAINT MONO (-6135 735);
FORCEPROP 0 LASTPIN (-6125 675) $PN Y37
J 2
(-6135 685);
DISPLAY 0.489362 (-6135 685);
PAINT MONO (-6135 685);
FORCEPROP 0 LASTPIN (-6125 625) $PN Y39
J 2
(-6135 635);
DISPLAY 0.489362 (-6135 635);
PAINT MONO (-6135 635);
FORCEPROP 0 LASTPIN (-6125 575) $PN Y42
J 2
(-6135 585);
DISPLAY 0.489362 (-6135 585);
PAINT MONO (-6135 585);
FORCEPROP 0 LASTPIN (-6125 525) $PN Y43
J 2
(-6135 535);
DISPLAY 0.489362 (-6135 535);
PAINT MONO (-6135 535);
FORCEPROP 0 LASTPIN (-5025 6325) $PN Y44
J 0
(-5015 6335);
DISPLAY 0.489362 (-5015 6335);
PAINT MONO (-5015 6335);
FORCEPROP 0 LASTPIN (-5025 6275) $PN Y45
J 0
(-5015 6285);
DISPLAY 0.489362 (-5015 6285);
PAINT MONO (-5015 6285);
FORCEPROP 0 LASTPIN (-5025 6225) $PN Y48
J 0
(-5015 6235);
DISPLAY 0.489362 (-5015 6235);
PAINT MONO (-5015 6235);
FORCEPROP 0 LASTPIN (-5025 6175) $PN Y49
J 0
(-5015 6185);
DISPLAY 0.489362 (-5015 6185);
PAINT MONO (-5015 6185);
FORCEPROP 0 LASTPIN (-5025 6125) $PN Y50
J 0
(-5015 6135);
DISPLAY 0.489362 (-5015 6135);
PAINT MONO (-5015 6135);
FORCEPROP 0 LASTPIN (-5025 6075) $PN Y51
J 0
(-5015 6085);
DISPLAY 0.489362 (-5015 6085);
PAINT MONO (-5015 6085);
FORCEPROP 0 LASTPIN (-5025 6025) $PN Y52
J 0
(-5015 6035);
DISPLAY 0.489362 (-5015 6035);
PAINT MONO (-5015 6035);
FORCEPROP 0 LASTPIN (-5025 5975) $PN Y53
J 0
(-5015 5985);
DISPLAY 0.489362 (-5015 5985);
PAINT MONO (-5015 5985);
FORCEPROP 0 LASTPIN (-5025 5925) $PN Y54
J 0
(-5015 5935);
DISPLAY 0.489362 (-5015 5935);
PAINT MONO (-5015 5935);
FORCEPROP 0 LASTPIN (-5025 5875) $PN Y59
J 0
(-5015 5885);
DISPLAY 0.489362 (-5015 5885);
PAINT MONO (-5015 5885);
FORCEPROP 0 LASTPIN (-5025 5825) $PN Y61
J 0
(-5015 5835);
DISPLAY 0.489362 (-5015 5835);
PAINT MONO (-5015 5835);
FORCEPROP 0 LASTPIN (-5025 5775) $PN Y66
J 0
(-5015 5785);
DISPLAY 0.489362 (-5015 5785);
PAINT MONO (-5015 5785);
FORCEPROP 0 LASTPIN (-5025 5725) $PN Y68
J 0
(-5015 5735);
DISPLAY 0.489362 (-5015 5735);
PAINT MONO (-5015 5735);
FORCEPROP 0 LASTPIN (-5025 5675) $PN Y73
J 0
(-5015 5685);
DISPLAY 0.489362 (-5015 5685);
PAINT MONO (-5015 5685);
FORCEPROP 2 LAST PART_TYPE SMLF
J 0
(-5975 6725);
DISPLAY 1.021277 (-5975 6725);
FORCEPROP 1 LAST MATERIAL IO
J 0
(-5970 6557);
DISPLAY 0.489362 (-5970 6557);
PAINT SKYBLUE (-5970 6557);
FORCEPROP 2 LAST VALUE SOCKET6096_13568-001
J 0
(-5975 6600);
DISPLAY 0.489362 (-5975 6600);
PAINT SKYBLUE (-5975 6600);
FORCEPROP 1 LAST PART_NUMBER DGA^6000030
J 0
(-5970 6684);
DISPLAY 0.489362 (-5970 6684);
PAINT SKYBLUE (-5970 6684);
FORCEPROP 2 LAST CDS_LIB pure_quanta
J 0
(-5575 3475);
DISPLAY INVISIBLE (-5575 3475);
FORCEPROP 1 LAST CDS_LMAN_SYM_OUTLINE -400,3050,400,-3050
J 0
(-5575 3475);
DISPLAY 0.468085 (-5575 3475);
PAINT GREEN (-5575 3475);
DISPLAY INVISIBLE (-5575 3475);
FORCEPROP 1 LAST NEEDS_NO_SIZE TRUE
J 0
(-5575 3475);
DISPLAY 0.723404 (-5575 3475);
PAINT GREEN (-5575 3475);
DISPLAY INVISIBLE (-5575 3475);
FORCEPROP 1 LAST PATH I12
J 0
(-5575 3475);
DISPLAY 0.723404 (-5575 3475);
PAINT GREEN (-5575 3475);
DISPLAY INVISIBLE (-5575 3475);
FORCEADD GENOA_SP5..29
(-7050 3450);
FORCEPROP 1 LAST LOCATION U26
J 0
(-7450 6625);
DISPLAY 0.489362 (-7450 6625);
PAINT SKYBLUE (-7450 6625);
FORCEPROP 0 LAST $SEC 29
J 0
(-7425 6850);
DISPLAY 0.680851 (-7425 6850);
PAINT MONO (-7425 6850);
DISPLAY INVISIBLE (-7425 6850);
FORCEPROP 0 LAST CDS_SEC 29
J 0
(-7425 6850);
DISPLAY 1.021277 (-7425 6850);
DISPLAY INVISIBLE (-7425 6850);
FORCEPROP 0 LASTPIN (-7600 6300) $PN J15
J 2
(-7610 6310);
DISPLAY 0.489362 (-7610 6310);
PAINT MONO (-7610 6310);
FORCEPROP 0 LASTPIN (-7600 6250) $PN J18
J 2
(-7610 6260);
DISPLAY 0.489362 (-7610 6260);
PAINT MONO (-7610 6260);
FORCEPROP 0 LASTPIN (-7600 6200) $PN J20
J 2
(-7610 6210);
DISPLAY 0.489362 (-7610 6210);
PAINT MONO (-7610 6210);
FORCEPROP 0 LASTPIN (-7600 6150) $PN J22
J 2
(-7610 6160);
DISPLAY 0.489362 (-7610 6160);
PAINT MONO (-7610 6160);
FORCEPROP 0 LASTPIN (-7600 6100) $PN J25
J 2
(-7610 6110);
DISPLAY 0.489362 (-7610 6110);
PAINT MONO (-7610 6110);
FORCEPROP 0 LASTPIN (-7600 6050) $PN J28
J 2
(-7610 6060);
DISPLAY 0.489362 (-7610 6060);
PAINT MONO (-7610 6060);
FORCEPROP 0 LASTPIN (-7600 6000) $PN J31
J 2
(-7610 6010);
DISPLAY 0.489362 (-7610 6010);
PAINT MONO (-7610 6010);
FORCEPROP 0 LASTPIN (-7600 5950) $PN J34
J 2
(-7610 5960);
DISPLAY 0.489362 (-7610 5960);
PAINT MONO (-7610 5960);
FORCEPROP 0 LASTPIN (-7600 5900) $PN J42
J 2
(-7610 5910);
DISPLAY 0.489362 (-7610 5910);
PAINT MONO (-7610 5910);
FORCEPROP 0 LASTPIN (-7600 5850) $PN J45
J 2
(-7610 5860);
DISPLAY 0.489362 (-7610 5860);
PAINT MONO (-7610 5860);
FORCEPROP 0 LASTPIN (-7600 5800) $PN J48
J 2
(-7610 5810);
DISPLAY 0.489362 (-7610 5810);
PAINT MONO (-7610 5810);
FORCEPROP 0 LASTPIN (-7600 5750) $PN J51
J 2
(-7610 5760);
DISPLAY 0.489362 (-7610 5760);
PAINT MONO (-7610 5760);
FORCEPROP 0 LASTPIN (-7600 5700) $PN J54
J 2
(-7610 5710);
DISPLAY 0.489362 (-7610 5710);
PAINT MONO (-7610 5710);
FORCEPROP 0 LASTPIN (-7600 5650) $PN J56
J 2
(-7610 5660);
DISPLAY 0.489362 (-7610 5660);
PAINT MONO (-7610 5660);
FORCEPROP 0 LASTPIN (-7600 5600) $PN J58
J 2
(-7610 5610);
DISPLAY 0.489362 (-7610 5610);
PAINT MONO (-7610 5610);
FORCEPROP 0 LASTPIN (-7600 5550) $PN J61
J 2
(-7610 5560);
DISPLAY 0.489362 (-7610 5560);
PAINT MONO (-7610 5560);
FORCEPROP 0 LASTPIN (-7600 5500) $PN J63
J 2
(-7610 5510);
DISPLAY 0.489362 (-7610 5510);
PAINT MONO (-7610 5510);
FORCEPROP 0 LASTPIN (-7600 5450) $PN J65
J 2
(-7610 5460);
DISPLAY 0.489362 (-7610 5460);
PAINT MONO (-7610 5460);
FORCEPROP 0 LASTPIN (-7600 5400) $PN J68
J 2
(-7610 5410);
DISPLAY 0.489362 (-7610 5410);
PAINT MONO (-7610 5410);
FORCEPROP 0 LASTPIN (-7600 5350) $PN J70
J 2
(-7610 5360);
DISPLAY 0.489362 (-7610 5360);
PAINT MONO (-7610 5360);
FORCEPROP 0 LASTPIN (-7600 5300) $PN J72
J 2
(-7610 5310);
DISPLAY 0.489362 (-7610 5310);
PAINT MONO (-7610 5310);
FORCEPROP 0 LASTPIN (-7600 5250) $PN J75
J 2
(-7610 5260);
DISPLAY 0.489362 (-7610 5260);
PAINT MONO (-7610 5260);
FORCEPROP 0 LASTPIN (-7600 5200) $PN K3
J 2
(-7610 5210);
DISPLAY 0.489362 (-7610 5210);
PAINT MONO (-7610 5210);
FORCEPROP 0 LASTPIN (-7600 5150) $PN K5
J 2
(-7610 5160);
DISPLAY 0.489362 (-7610 5160);
PAINT MONO (-7610 5160);
FORCEPROP 0 LASTPIN (-7600 5100) $PN K8
J 2
(-7610 5110);
DISPLAY 0.489362 (-7610 5110);
PAINT MONO (-7610 5110);
FORCEPROP 0 LASTPIN (-7600 5050) $PN K10
J 2
(-7610 5060);
DISPLAY 0.489362 (-7610 5060);
PAINT MONO (-7610 5060);
FORCEPROP 0 LASTPIN (-7600 5000) $PN K12
J 2
(-7610 5010);
DISPLAY 0.489362 (-7610 5010);
PAINT MONO (-7610 5010);
FORCEPROP 0 LASTPIN (-7600 4950) $PN K15
J 2
(-7610 4960);
DISPLAY 0.489362 (-7610 4960);
PAINT MONO (-7610 4960);
FORCEPROP 0 LASTPIN (-7600 4900) $PN K17
J 2
(-7610 4910);
DISPLAY 0.489362 (-7610 4910);
PAINT MONO (-7610 4910);
FORCEPROP 0 LASTPIN (-7600 4850) $PN K19
J 2
(-7610 4860);
DISPLAY 0.489362 (-7610 4860);
PAINT MONO (-7610 4860);
FORCEPROP 0 LASTPIN (-7600 4800) $PN K24
J 2
(-7610 4810);
DISPLAY 0.489362 (-7610 4810);
PAINT MONO (-7610 4810);
FORCEPROP 0 LASTPIN (-7600 4750) $PN K25
J 2
(-7610 4760);
DISPLAY 0.489362 (-7610 4760);
PAINT MONO (-7610 4760);
FORCEPROP 0 LASTPIN (-7600 4700) $PN K26
J 2
(-7610 4710);
DISPLAY 0.489362 (-7610 4710);
PAINT MONO (-7610 4710);
FORCEPROP 0 LASTPIN (-7600 4650) $PN K27
J 2
(-7610 4660);
DISPLAY 0.489362 (-7610 4660);
PAINT MONO (-7610 4660);
FORCEPROP 0 LASTPIN (-7600 4600) $PN K28
J 2
(-7610 4610);
DISPLAY 0.489362 (-7610 4610);
PAINT MONO (-7610 4610);
FORCEPROP 0 LASTPIN (-7600 4550) $PN K29
J 2
(-7610 4560);
DISPLAY 0.489362 (-7610 4560);
PAINT MONO (-7610 4560);
FORCEPROP 0 LASTPIN (-7600 4500) $PN K30
J 2
(-7610 4510);
DISPLAY 0.489362 (-7610 4510);
PAINT MONO (-7610 4510);
FORCEPROP 0 LASTPIN (-7600 4450) $PN K31
J 2
(-7610 4460);
DISPLAY 0.489362 (-7610 4460);
PAINT MONO (-7610 4460);
FORCEPROP 0 LASTPIN (-7600 4400) $PN K32
J 2
(-7610 4410);
DISPLAY 0.489362 (-7610 4410);
PAINT MONO (-7610 4410);
FORCEPROP 0 LASTPIN (-7600 4350) $PN K33
J 2
(-7610 4360);
DISPLAY 0.489362 (-7610 4360);
PAINT MONO (-7610 4360);
FORCEPROP 0 LASTPIN (-7600 4300) $PN K34
J 2
(-7610 4310);
DISPLAY 0.489362 (-7610 4310);
PAINT MONO (-7610 4310);
FORCEPROP 0 LASTPIN (-7600 4250) $PN K37
J 2
(-7610 4260);
DISPLAY 0.489362 (-7610 4260);
PAINT MONO (-7610 4260);
FORCEPROP 0 LASTPIN (-7600 4200) $PN K39
J 2
(-7610 4210);
DISPLAY 0.489362 (-7610 4210);
PAINT MONO (-7610 4210);
FORCEPROP 0 LASTPIN (-7600 4150) $PN K42
J 2
(-7610 4160);
DISPLAY 0.489362 (-7610 4160);
PAINT MONO (-7610 4160);
FORCEPROP 0 LASTPIN (-7600 4100) $PN K43
J 2
(-7610 4110);
DISPLAY 0.489362 (-7610 4110);
PAINT MONO (-7610 4110);
FORCEPROP 0 LASTPIN (-7600 4050) $PN K44
J 2
(-7610 4060);
DISPLAY 0.489362 (-7610 4060);
PAINT MONO (-7610 4060);
FORCEPROP 0 LASTPIN (-7600 4000) $PN K45
J 2
(-7610 4010);
DISPLAY 0.489362 (-7610 4010);
PAINT MONO (-7610 4010);
FORCEPROP 0 LASTPIN (-7600 3950) $PN K46
J 2
(-7610 3960);
DISPLAY 0.489362 (-7610 3960);
PAINT MONO (-7610 3960);
FORCEPROP 0 LASTPIN (-7600 3900) $PN K47
J 2
(-7610 3910);
DISPLAY 0.489362 (-7610 3910);
PAINT MONO (-7610 3910);
FORCEPROP 0 LASTPIN (-7600 3850) $PN K48
J 2
(-7610 3860);
DISPLAY 0.489362 (-7610 3860);
PAINT MONO (-7610 3860);
FORCEPROP 0 LASTPIN (-7600 3800) $PN K49
J 2
(-7610 3810);
DISPLAY 0.489362 (-7610 3810);
PAINT MONO (-7610 3810);
FORCEPROP 0 LASTPIN (-7600 3750) $PN K50
J 2
(-7610 3760);
DISPLAY 0.489362 (-7610 3760);
PAINT MONO (-7610 3760);
FORCEPROP 0 LASTPIN (-7600 3700) $PN K51
J 2
(-7610 3710);
DISPLAY 0.489362 (-7610 3710);
PAINT MONO (-7610 3710);
FORCEPROP 0 LASTPIN (-7600 3650) $PN K52
J 2
(-7610 3660);
DISPLAY 0.489362 (-7610 3660);
PAINT MONO (-7610 3660);
FORCEPROP 0 LASTPIN (-7600 3600) $PN K53
J 2
(-7610 3610);
DISPLAY 0.489362 (-7610 3610);
PAINT MONO (-7610 3610);
FORCEPROP 0 LASTPIN (-7600 3550) $PN K57
J 2
(-7610 3560);
DISPLAY 0.489362 (-7610 3560);
PAINT MONO (-7610 3560);
FORCEPROP 0 LASTPIN (-7600 3500) $PN K61
J 2
(-7610 3510);
DISPLAY 0.489362 (-7610 3510);
PAINT MONO (-7610 3510);
FORCEPROP 0 LASTPIN (-7600 3450) $PN K64
J 2
(-7610 3460);
DISPLAY 0.489362 (-7610 3460);
PAINT MONO (-7610 3460);
FORCEPROP 0 LASTPIN (-7600 3400) $PN K66
J 2
(-7610 3410);
DISPLAY 0.489362 (-7610 3410);
PAINT MONO (-7610 3410);
FORCEPROP 0 LASTPIN (-7600 3350) $PN K68
J 2
(-7610 3360);
DISPLAY 0.489362 (-7610 3360);
PAINT MONO (-7610 3360);
FORCEPROP 0 LASTPIN (-7600 3300) $PN K71
J 2
(-7610 3310);
DISPLAY 0.489362 (-7610 3310);
PAINT MONO (-7610 3310);
FORCEPROP 0 LASTPIN (-7600 3250) $PN K73
J 2
(-7610 3260);
DISPLAY 0.489362 (-7610 3260);
PAINT MONO (-7610 3260);
FORCEPROP 0 LASTPIN (-7600 3200) $PN L1
J 2
(-7610 3210);
DISPLAY 0.489362 (-7610 3210);
PAINT MONO (-7610 3210);
FORCEPROP 0 LASTPIN (-7600 3150) $PN L6
J 2
(-7610 3160);
DISPLAY 0.489362 (-7610 3160);
PAINT MONO (-7610 3160);
FORCEPROP 0 LASTPIN (-7600 3100) $PN L8
J 2
(-7610 3110);
DISPLAY 0.489362 (-7610 3110);
PAINT MONO (-7610 3110);
FORCEPROP 0 LASTPIN (-7600 3050) $PN L13
J 2
(-7610 3060);
DISPLAY 0.489362 (-7610 3060);
PAINT MONO (-7610 3060);
FORCEPROP 0 LASTPIN (-7600 3000) $PN L15
J 2
(-7610 3010);
DISPLAY 0.489362 (-7610 3010);
PAINT MONO (-7610 3010);
FORCEPROP 0 LASTPIN (-7600 2950) $PN L20
J 2
(-7610 2960);
DISPLAY 0.489362 (-7610 2960);
PAINT MONO (-7610 2960);
FORCEPROP 0 LASTPIN (-7600 2900) $PN L22
J 2
(-7610 2910);
DISPLAY 0.489362 (-7610 2910);
PAINT MONO (-7610 2910);
FORCEPROP 0 LASTPIN (-7600 2850) $PN L25
J 2
(-7610 2860);
DISPLAY 0.489362 (-7610 2860);
PAINT MONO (-7610 2860);
FORCEPROP 0 LASTPIN (-7600 2800) $PN L28
J 2
(-7610 2810);
DISPLAY 0.489362 (-7610 2810);
PAINT MONO (-7610 2810);
FORCEPROP 0 LASTPIN (-7600 2750) $PN L31
J 2
(-7610 2760);
DISPLAY 0.489362 (-7610 2760);
PAINT MONO (-7610 2760);
FORCEPROP 0 LASTPIN (-7600 2700) $PN L34
J 2
(-7610 2710);
DISPLAY 0.489362 (-7610 2710);
PAINT MONO (-7610 2710);
FORCEPROP 0 LASTPIN (-7600 2650) $PN L35
J 2
(-7610 2660);
DISPLAY 0.489362 (-7610 2660);
PAINT MONO (-7610 2660);
FORCEPROP 0 LASTPIN (-7600 2600) $PN L36
J 2
(-7610 2610);
DISPLAY 0.489362 (-7610 2610);
PAINT MONO (-7610 2610);
FORCEPROP 0 LASTPIN (-7600 2550) $PN L40
J 2
(-7610 2560);
DISPLAY 0.489362 (-7610 2560);
PAINT MONO (-7610 2560);
FORCEPROP 0 LASTPIN (-7600 2500) $PN L41
J 2
(-7610 2510);
DISPLAY 0.489362 (-7610 2510);
PAINT MONO (-7610 2510);
FORCEPROP 0 LASTPIN (-7600 2450) $PN L42
J 2
(-7610 2460);
DISPLAY 0.489362 (-7610 2460);
PAINT MONO (-7610 2460);
FORCEPROP 0 LASTPIN (-7600 2400) $PN L45
J 2
(-7610 2410);
DISPLAY 0.489362 (-7610 2410);
PAINT MONO (-7610 2410);
FORCEPROP 0 LASTPIN (-7600 2350) $PN L48
J 2
(-7610 2360);
DISPLAY 0.489362 (-7610 2360);
PAINT MONO (-7610 2360);
FORCEPROP 0 LASTPIN (-7600 2300) $PN L51
J 2
(-7610 2310);
DISPLAY 0.489362 (-7610 2310);
PAINT MONO (-7610 2310);
FORCEPROP 0 LASTPIN (-7600 2250) $PN L54
J 2
(-7610 2260);
DISPLAY 0.489362 (-7610 2260);
PAINT MONO (-7610 2260);
FORCEPROP 0 LASTPIN (-7600 2200) $PN L56
J 2
(-7610 2210);
DISPLAY 0.489362 (-7610 2210);
PAINT MONO (-7610 2210);
FORCEPROP 0 LASTPIN (-7600 2150) $PN L61
J 2
(-7610 2160);
DISPLAY 0.489362 (-7610 2160);
PAINT MONO (-7610 2160);
FORCEPROP 0 LASTPIN (-7600 2100) $PN L63
J 2
(-7610 2110);
DISPLAY 0.489362 (-7610 2110);
PAINT MONO (-7610 2110);
FORCEPROP 0 LASTPIN (-7600 2050) $PN L68
J 2
(-7610 2060);
DISPLAY 0.489362 (-7610 2060);
PAINT MONO (-7610 2060);
FORCEPROP 0 LASTPIN (-7600 2000) $PN L70
J 2
(-7610 2010);
DISPLAY 0.489362 (-7610 2010);
PAINT MONO (-7610 2010);
FORCEPROP 0 LASTPIN (-7600 1950) $PN L75
J 2
(-7610 1960);
DISPLAY 0.489362 (-7610 1960);
PAINT MONO (-7610 1960);
FORCEPROP 0 LASTPIN (-7600 1900) $PN M3
J 2
(-7610 1910);
DISPLAY 0.489362 (-7610 1910);
PAINT MONO (-7610 1910);
FORCEPROP 0 LASTPIN (-7600 1850) $PN M5
J 2
(-7610 1860);
DISPLAY 0.489362 (-7610 1860);
PAINT MONO (-7610 1860);
FORCEPROP 0 LASTPIN (-7600 1800) $PN M8
J 2
(-7610 1810);
DISPLAY 0.489362 (-7610 1810);
PAINT MONO (-7610 1810);
FORCEPROP 0 LASTPIN (-7600 1750) $PN M10
J 2
(-7610 1760);
DISPLAY 0.489362 (-7610 1760);
PAINT MONO (-7610 1760);
FORCEPROP 0 LASTPIN (-7600 1700) $PN M12
J 2
(-7610 1710);
DISPLAY 0.489362 (-7610 1710);
PAINT MONO (-7610 1710);
FORCEPROP 0 LASTPIN (-7600 1650) $PN M15
J 2
(-7610 1660);
DISPLAY 0.489362 (-7610 1660);
PAINT MONO (-7610 1660);
FORCEPROP 0 LASTPIN (-7600 1600) $PN M17
J 2
(-7610 1610);
DISPLAY 0.489362 (-7610 1610);
PAINT MONO (-7610 1610);
FORCEPROP 0 LASTPIN (-7600 1550) $PN M19
J 2
(-7610 1560);
DISPLAY 0.489362 (-7610 1560);
PAINT MONO (-7610 1560);
FORCEPROP 0 LASTPIN (-7600 1500) $PN M22
J 2
(-7610 1510);
DISPLAY 0.489362 (-7610 1510);
PAINT MONO (-7610 1510);
FORCEPROP 0 LASTPIN (-7600 1450) $PN M25
J 2
(-7610 1460);
DISPLAY 0.489362 (-7610 1460);
PAINT MONO (-7610 1460);
FORCEPROP 0 LASTPIN (-7600 1400) $PN M28
J 2
(-7610 1410);
DISPLAY 0.489362 (-7610 1410);
PAINT MONO (-7610 1410);
FORCEPROP 0 LASTPIN (-7600 1350) $PN M31
J 2
(-7610 1360);
DISPLAY 0.489362 (-7610 1360);
PAINT MONO (-7610 1360);
FORCEPROP 0 LASTPIN (-7600 1300) $PN M34
J 2
(-7610 1310);
DISPLAY 0.489362 (-7610 1310);
PAINT MONO (-7610 1310);
FORCEPROP 0 LASTPIN (-7600 1250) $PN M37
J 2
(-7610 1260);
DISPLAY 0.489362 (-7610 1260);
PAINT MONO (-7610 1260);
FORCEPROP 0 LASTPIN (-7600 1200) $PN M39
J 2
(-7610 1210);
DISPLAY 0.489362 (-7610 1210);
PAINT MONO (-7610 1210);
FORCEPROP 0 LASTPIN (-7600 1150) $PN M42
J 2
(-7610 1160);
DISPLAY 0.489362 (-7610 1160);
PAINT MONO (-7610 1160);
FORCEPROP 0 LASTPIN (-7600 1100) $PN M45
J 2
(-7610 1110);
DISPLAY 0.489362 (-7610 1110);
PAINT MONO (-7610 1110);
FORCEPROP 0 LASTPIN (-7600 1050) $PN M48
J 2
(-7610 1060);
DISPLAY 0.489362 (-7610 1060);
PAINT MONO (-7610 1060);
FORCEPROP 0 LASTPIN (-7600 1000) $PN M51
J 2
(-7610 1010);
DISPLAY 0.489362 (-7610 1010);
PAINT MONO (-7610 1010);
FORCEPROP 0 LASTPIN (-7600 950) $PN M54
J 2
(-7610 960);
DISPLAY 0.489362 (-7610 960);
PAINT MONO (-7610 960);
FORCEPROP 0 LASTPIN (-7600 900) $PN M57
J 2
(-7610 910);
DISPLAY 0.489362 (-7610 910);
PAINT MONO (-7610 910);
FORCEPROP 0 LASTPIN (-7600 850) $PN M59
J 2
(-7610 860);
DISPLAY 0.489362 (-7610 860);
PAINT MONO (-7610 860);
FORCEPROP 0 LASTPIN (-7600 800) $PN M61
J 2
(-7610 810);
DISPLAY 0.489362 (-7610 810);
PAINT MONO (-7610 810);
FORCEPROP 0 LASTPIN (-7600 750) $PN M64
J 2
(-7610 760);
DISPLAY 0.489362 (-7610 760);
PAINT MONO (-7610 760);
FORCEPROP 0 LASTPIN (-7600 700) $PN M66
J 2
(-7610 710);
DISPLAY 0.489362 (-7610 710);
PAINT MONO (-7610 710);
FORCEPROP 0 LASTPIN (-7600 650) $PN M68
J 2
(-7610 660);
DISPLAY 0.489362 (-7610 660);
PAINT MONO (-7610 660);
FORCEPROP 0 LASTPIN (-7600 600) $PN M71
J 2
(-7610 610);
DISPLAY 0.489362 (-7610 610);
PAINT MONO (-7610 610);
FORCEPROP 0 LASTPIN (-7600 550) $PN M73
J 2
(-7610 560);
DISPLAY 0.489362 (-7610 560);
PAINT MONO (-7610 560);
FORCEPROP 0 LASTPIN (-7600 500) $PN N1
J 2
(-7610 510);
DISPLAY 0.489362 (-7610 510);
PAINT MONO (-7610 510);
FORCEPROP 0 LASTPIN (-6500 6300) $PN N4
J 0
(-6490 6310);
DISPLAY 0.489362 (-6490 6310);
PAINT MONO (-6490 6310);
FORCEPROP 0 LASTPIN (-6500 6250) $PN N6
J 0
(-6490 6260);
DISPLAY 0.489362 (-6490 6260);
PAINT MONO (-6490 6260);
FORCEPROP 0 LASTPIN (-6500 6200) $PN N8
J 0
(-6490 6210);
DISPLAY 0.489362 (-6490 6210);
PAINT MONO (-6490 6210);
FORCEPROP 0 LASTPIN (-6500 6150) $PN N11
J 0
(-6490 6160);
DISPLAY 0.489362 (-6490 6160);
PAINT MONO (-6490 6160);
FORCEPROP 0 LASTPIN (-6500 6100) $PN N13
J 0
(-6490 6110);
DISPLAY 0.489362 (-6490 6110);
PAINT MONO (-6490 6110);
FORCEPROP 0 LASTPIN (-6500 6050) $PN N15
J 0
(-6490 6060);
DISPLAY 0.489362 (-6490 6060);
PAINT MONO (-6490 6060);
FORCEPROP 0 LASTPIN (-6500 6000) $PN N18
J 0
(-6490 6010);
DISPLAY 0.489362 (-6490 6010);
PAINT MONO (-6490 6010);
FORCEPROP 0 LASTPIN (-6500 5950) $PN N20
J 0
(-6490 5960);
DISPLAY 0.489362 (-6490 5960);
PAINT MONO (-6490 5960);
FORCEPROP 0 LASTPIN (-6500 5900) $PN N22
J 0
(-6490 5910);
DISPLAY 0.489362 (-6490 5910);
PAINT MONO (-6490 5910);
FORCEPROP 0 LASTPIN (-6500 5850) $PN N25
J 0
(-6490 5860);
DISPLAY 0.489362 (-6490 5860);
PAINT MONO (-6490 5860);
FORCEPROP 0 LASTPIN (-6500 5800) $PN N28
J 0
(-6490 5810);
DISPLAY 0.489362 (-6490 5810);
PAINT MONO (-6490 5810);
FORCEPROP 0 LASTPIN (-6500 5750) $PN N31
J 0
(-6490 5760);
DISPLAY 0.489362 (-6490 5760);
PAINT MONO (-6490 5760);
FORCEPROP 0 LASTPIN (-6500 5700) $PN N34
J 0
(-6490 5710);
DISPLAY 0.489362 (-6490 5710);
PAINT MONO (-6490 5710);
FORCEPROP 0 LASTPIN (-6500 5650) $PN N42
J 0
(-6490 5660);
DISPLAY 0.489362 (-6490 5660);
PAINT MONO (-6490 5660);
FORCEPROP 0 LASTPIN (-6500 5600) $PN N45
J 0
(-6490 5610);
DISPLAY 0.489362 (-6490 5610);
PAINT MONO (-6490 5610);
FORCEPROP 0 LASTPIN (-6500 5550) $PN N48
J 0
(-6490 5560);
DISPLAY 0.489362 (-6490 5560);
PAINT MONO (-6490 5560);
FORCEPROP 0 LASTPIN (-6500 5500) $PN N51
J 0
(-6490 5510);
DISPLAY 0.489362 (-6490 5510);
PAINT MONO (-6490 5510);
FORCEPROP 0 LASTPIN (-6500 5450) $PN N54
J 0
(-6490 5460);
DISPLAY 0.489362 (-6490 5460);
PAINT MONO (-6490 5460);
FORCEPROP 0 LASTPIN (-6500 5400) $PN N56
J 0
(-6490 5410);
DISPLAY 0.489362 (-6490 5410);
PAINT MONO (-6490 5410);
FORCEPROP 0 LASTPIN (-6500 5350) $PN N58
J 0
(-6490 5360);
DISPLAY 0.489362 (-6490 5360);
PAINT MONO (-6490 5360);
FORCEPROP 0 LASTPIN (-6500 5300) $PN N61
J 0
(-6490 5310);
DISPLAY 0.489362 (-6490 5310);
PAINT MONO (-6490 5310);
FORCEPROP 0 LASTPIN (-6500 5250) $PN N63
J 0
(-6490 5260);
DISPLAY 0.489362 (-6490 5260);
PAINT MONO (-6490 5260);
FORCEPROP 0 LASTPIN (-6500 5200) $PN N65
J 0
(-6490 5210);
DISPLAY 0.489362 (-6490 5210);
PAINT MONO (-6490 5210);
FORCEPROP 0 LASTPIN (-6500 5150) $PN N68
J 0
(-6490 5160);
DISPLAY 0.489362 (-6490 5160);
PAINT MONO (-6490 5160);
FORCEPROP 0 LASTPIN (-6500 5100) $PN N70
J 0
(-6490 5110);
DISPLAY 0.489362 (-6490 5110);
PAINT MONO (-6490 5110);
FORCEPROP 0 LASTPIN (-6500 5050) $PN N72
J 0
(-6490 5060);
DISPLAY 0.489362 (-6490 5060);
PAINT MONO (-6490 5060);
FORCEPROP 0 LASTPIN (-6500 5000) $PN N75
J 0
(-6490 5010);
DISPLAY 0.489362 (-6490 5010);
PAINT MONO (-6490 5010);
FORCEPROP 0 LASTPIN (-6500 4950) $PN P3
J 0
(-6490 4960);
DISPLAY 0.489362 (-6490 4960);
PAINT MONO (-6490 4960);
FORCEPROP 0 LASTPIN (-6500 4900) $PN P8
J 0
(-6490 4910);
DISPLAY 0.489362 (-6490 4910);
PAINT MONO (-6490 4910);
FORCEPROP 0 LASTPIN (-6500 4850) $PN P10
J 0
(-6490 4860);
DISPLAY 0.489362 (-6490 4860);
PAINT MONO (-6490 4860);
FORCEPROP 0 LASTPIN (-6500 4800) $PN P15
J 0
(-6490 4810);
DISPLAY 0.489362 (-6490 4810);
PAINT MONO (-6490 4810);
FORCEPROP 0 LASTPIN (-6500 4750) $PN P17
J 0
(-6490 4760);
DISPLAY 0.489362 (-6490 4760);
PAINT MONO (-6490 4760);
FORCEPROP 0 LASTPIN (-6500 4700) $PN P23
J 0
(-6490 4710);
DISPLAY 0.489362 (-6490 4710);
PAINT MONO (-6490 4710);
FORCEPROP 0 LASTPIN (-6500 4650) $PN P24
J 0
(-6490 4660);
DISPLAY 0.489362 (-6490 4660);
PAINT MONO (-6490 4660);
FORCEPROP 0 LASTPIN (-6500 4600) $PN P26
J 0
(-6490 4610);
DISPLAY 0.489362 (-6490 4610);
PAINT MONO (-6490 4610);
FORCEPROP 0 LASTPIN (-6500 4550) $PN P27
J 0
(-6490 4560);
DISPLAY 0.489362 (-6490 4560);
PAINT MONO (-6490 4560);
FORCEPROP 0 LASTPIN (-6500 4500) $PN P28
J 0
(-6490 4510);
DISPLAY 0.489362 (-6490 4510);
PAINT MONO (-6490 4510);
FORCEPROP 0 LASTPIN (-6500 4450) $PN P29
J 0
(-6490 4460);
DISPLAY 0.489362 (-6490 4460);
PAINT MONO (-6490 4460);
FORCEPROP 0 LASTPIN (-6500 4400) $PN P30
J 0
(-6490 4410);
DISPLAY 0.489362 (-6490 4410);
PAINT MONO (-6490 4410);
FORCEPROP 0 LASTPIN (-6500 4350) $PN P31
J 0
(-6490 4360);
DISPLAY 0.489362 (-6490 4360);
PAINT MONO (-6490 4360);
FORCEPROP 0 LASTPIN (-6500 4300) $PN P32
J 0
(-6490 4310);
DISPLAY 0.489362 (-6490 4310);
PAINT MONO (-6490 4310);
FORCEPROP 0 LASTPIN (-6500 4250) $PN P33
J 0
(-6490 4260);
DISPLAY 0.489362 (-6490 4260);
PAINT MONO (-6490 4260);
FORCEPROP 0 LASTPIN (-6500 4200) $PN P34
J 0
(-6490 4210);
DISPLAY 0.489362 (-6490 4210);
PAINT MONO (-6490 4210);
FORCEPROP 0 LASTPIN (-6500 4150) $PN P37
J 0
(-6490 4160);
DISPLAY 0.489362 (-6490 4160);
PAINT MONO (-6490 4160);
FORCEPROP 0 LASTPIN (-6500 4100) $PN P39
J 0
(-6490 4110);
DISPLAY 0.489362 (-6490 4110);
PAINT MONO (-6490 4110);
FORCEPROP 0 LASTPIN (-6500 4050) $PN P42
J 0
(-6490 4060);
DISPLAY 0.489362 (-6490 4060);
PAINT MONO (-6490 4060);
FORCEPROP 0 LASTPIN (-6500 4000) $PN P43
J 0
(-6490 4010);
DISPLAY 0.489362 (-6490 4010);
PAINT MONO (-6490 4010);
FORCEPROP 0 LASTPIN (-6500 3950) $PN P44
J 0
(-6490 3960);
DISPLAY 0.489362 (-6490 3960);
PAINT MONO (-6490 3960);
FORCEPROP 0 LASTPIN (-6500 3900) $PN P45
J 0
(-6490 3910);
DISPLAY 0.489362 (-6490 3910);
PAINT MONO (-6490 3910);
FORCEPROP 0 LASTPIN (-6500 3850) $PN P46
J 0
(-6490 3860);
DISPLAY 0.489362 (-6490 3860);
PAINT MONO (-6490 3860);
FORCEPROP 0 LASTPIN (-6500 3800) $PN P47
J 0
(-6490 3810);
DISPLAY 0.489362 (-6490 3810);
PAINT MONO (-6490 3810);
FORCEPROP 0 LASTPIN (-6500 3750) $PN P48
J 0
(-6490 3760);
DISPLAY 0.489362 (-6490 3760);
PAINT MONO (-6490 3760);
FORCEPROP 0 LASTPIN (-6500 3700) $PN P49
J 0
(-6490 3710);
DISPLAY 0.489362 (-6490 3710);
PAINT MONO (-6490 3710);
FORCEPROP 0 LASTPIN (-6500 3650) $PN P50
J 0
(-6490 3660);
DISPLAY 0.489362 (-6490 3660);
PAINT MONO (-6490 3660);
FORCEPROP 0 LASTPIN (-6500 3600) $PN P51
J 0
(-6490 3610);
DISPLAY 0.489362 (-6490 3610);
PAINT MONO (-6490 3610);
FORCEPROP 0 LASTPIN (-6500 3550) $PN P52
J 0
(-6490 3560);
DISPLAY 0.489362 (-6490 3560);
PAINT MONO (-6490 3560);
FORCEPROP 0 LASTPIN (-6500 3500) $PN P53
J 0
(-6490 3510);
DISPLAY 0.489362 (-6490 3510);
PAINT MONO (-6490 3510);
FORCEPROP 0 LASTPIN (-6500 3450) $PN P59
J 0
(-6490 3460);
DISPLAY 0.489362 (-6490 3460);
PAINT MONO (-6490 3460);
FORCEPROP 0 LASTPIN (-6500 3400) $PN P61
J 0
(-6490 3410);
DISPLAY 0.489362 (-6490 3410);
PAINT MONO (-6490 3410);
FORCEPROP 0 LASTPIN (-6500 3350) $PN P66
J 0
(-6490 3360);
DISPLAY 0.489362 (-6490 3360);
PAINT MONO (-6490 3360);
FORCEPROP 0 LASTPIN (-6500 3300) $PN P73
J 0
(-6490 3310);
DISPLAY 0.489362 (-6490 3310);
PAINT MONO (-6490 3310);
FORCEPROP 0 LASTPIN (-6500 3250) $PN R1
J 0
(-6490 3260);
DISPLAY 0.489362 (-6490 3260);
PAINT MONO (-6490 3260);
FORCEPROP 0 LASTPIN (-6500 3200) $PN R4
J 0
(-6490 3210);
DISPLAY 0.489362 (-6490 3210);
PAINT MONO (-6490 3210);
FORCEPROP 0 LASTPIN (-6500 3150) $PN R6
J 0
(-6490 3160);
DISPLAY 0.489362 (-6490 3160);
PAINT MONO (-6490 3160);
FORCEPROP 0 LASTPIN (-6500 3100) $PN R8
J 0
(-6490 3110);
DISPLAY 0.489362 (-6490 3110);
PAINT MONO (-6490 3110);
FORCEPROP 0 LASTPIN (-6500 3050) $PN R11
J 0
(-6490 3060);
DISPLAY 0.489362 (-6490 3060);
PAINT MONO (-6490 3060);
FORCEPROP 0 LASTPIN (-6500 3000) $PN R13
J 0
(-6490 3010);
DISPLAY 0.489362 (-6490 3010);
PAINT MONO (-6490 3010);
FORCEPROP 0 LASTPIN (-6500 2950) $PN R15
J 0
(-6490 2960);
DISPLAY 0.489362 (-6490 2960);
PAINT MONO (-6490 2960);
FORCEPROP 0 LASTPIN (-6500 2900) $PN R18
J 0
(-6490 2910);
DISPLAY 0.489362 (-6490 2910);
PAINT MONO (-6490 2910);
FORCEPROP 0 LASTPIN (-6500 2850) $PN R20
J 0
(-6490 2860);
DISPLAY 0.489362 (-6490 2860);
PAINT MONO (-6490 2860);
FORCEPROP 0 LASTPIN (-6500 2800) $PN R22
J 0
(-6490 2810);
DISPLAY 0.489362 (-6490 2810);
PAINT MONO (-6490 2810);
FORCEPROP 0 LASTPIN (-6500 2750) $PN R25
J 0
(-6490 2760);
DISPLAY 0.489362 (-6490 2760);
PAINT MONO (-6490 2760);
FORCEPROP 0 LASTPIN (-6500 2700) $PN R28
J 0
(-6490 2710);
DISPLAY 0.489362 (-6490 2710);
PAINT MONO (-6490 2710);
FORCEPROP 0 LASTPIN (-6500 2650) $PN R31
J 0
(-6490 2660);
DISPLAY 0.489362 (-6490 2660);
PAINT MONO (-6490 2660);
FORCEPROP 0 LASTPIN (-6500 2600) $PN R34
J 0
(-6490 2610);
DISPLAY 0.489362 (-6490 2610);
PAINT MONO (-6490 2610);
FORCEPROP 0 LASTPIN (-6500 2550) $PN R35
J 0
(-6490 2560);
DISPLAY 0.489362 (-6490 2560);
PAINT MONO (-6490 2560);
FORCEPROP 0 LASTPIN (-6500 2500) $PN R36
J 0
(-6490 2510);
DISPLAY 0.489362 (-6490 2510);
PAINT MONO (-6490 2510);
FORCEPROP 0 LASTPIN (-6500 2450) $PN R40
J 0
(-6490 2460);
DISPLAY 0.489362 (-6490 2460);
PAINT MONO (-6490 2460);
FORCEPROP 0 LASTPIN (-6500 2400) $PN R41
J 0
(-6490 2410);
DISPLAY 0.489362 (-6490 2410);
PAINT MONO (-6490 2410);
FORCEPROP 0 LASTPIN (-6500 2350) $PN R42
J 0
(-6490 2360);
DISPLAY 0.489362 (-6490 2360);
PAINT MONO (-6490 2360);
FORCEPROP 0 LASTPIN (-6500 2300) $PN R45
J 0
(-6490 2310);
DISPLAY 0.489362 (-6490 2310);
PAINT MONO (-6490 2310);
FORCEPROP 0 LASTPIN (-6500 2250) $PN R48
J 0
(-6490 2260);
DISPLAY 0.489362 (-6490 2260);
PAINT MONO (-6490 2260);
FORCEPROP 0 LASTPIN (-6500 2200) $PN R51
J 0
(-6490 2210);
DISPLAY 0.489362 (-6490 2210);
PAINT MONO (-6490 2210);
FORCEPROP 0 LASTPIN (-6500 2150) $PN R54
J 0
(-6490 2160);
DISPLAY 0.489362 (-6490 2160);
PAINT MONO (-6490 2160);
FORCEPROP 0 LASTPIN (-6500 2100) $PN R56
J 0
(-6490 2110);
DISPLAY 0.489362 (-6490 2110);
PAINT MONO (-6490 2110);
FORCEPROP 0 LASTPIN (-6500 2050) $PN R58
J 0
(-6490 2060);
DISPLAY 0.489362 (-6490 2060);
PAINT MONO (-6490 2060);
FORCEPROP 0 LASTPIN (-6500 2000) $PN R61
J 0
(-6490 2010);
DISPLAY 0.489362 (-6490 2010);
PAINT MONO (-6490 2010);
FORCEPROP 0 LASTPIN (-6500 1950) $PN R63
J 0
(-6490 1960);
DISPLAY 0.489362 (-6490 1960);
PAINT MONO (-6490 1960);
FORCEPROP 0 LASTPIN (-6500 1900) $PN R65
J 0
(-6490 1910);
DISPLAY 0.489362 (-6490 1910);
PAINT MONO (-6490 1910);
FORCEPROP 0 LASTPIN (-6500 1850) $PN R68
J 0
(-6490 1860);
DISPLAY 0.489362 (-6490 1860);
PAINT MONO (-6490 1860);
FORCEPROP 0 LASTPIN (-6500 1800) $PN R70
J 0
(-6490 1810);
DISPLAY 0.489362 (-6490 1810);
PAINT MONO (-6490 1810);
FORCEPROP 0 LASTPIN (-6500 1750) $PN R72
J 0
(-6490 1760);
DISPLAY 0.489362 (-6490 1760);
PAINT MONO (-6490 1760);
FORCEPROP 0 LASTPIN (-6500 1700) $PN R75
J 0
(-6490 1710);
DISPLAY 0.489362 (-6490 1710);
PAINT MONO (-6490 1710);
FORCEPROP 0 LASTPIN (-6500 1650) $PN T3
J 0
(-6490 1660);
DISPLAY 0.489362 (-6490 1660);
PAINT MONO (-6490 1660);
FORCEPROP 0 LASTPIN (-6500 1600) $PN T5
J 0
(-6490 1610);
DISPLAY 0.489362 (-6490 1610);
PAINT MONO (-6490 1610);
FORCEPROP 0 LASTPIN (-6500 1550) $PN T8
J 0
(-6490 1560);
DISPLAY 0.489362 (-6490 1560);
PAINT MONO (-6490 1560);
FORCEPROP 0 LASTPIN (-6500 1500) $PN T10
J 0
(-6490 1510);
DISPLAY 0.489362 (-6490 1510);
PAINT MONO (-6490 1510);
FORCEPROP 0 LASTPIN (-6500 1450) $PN T12
J 0
(-6490 1460);
DISPLAY 0.489362 (-6490 1460);
PAINT MONO (-6490 1460);
FORCEPROP 0 LASTPIN (-6500 1400) $PN T15
J 0
(-6490 1410);
DISPLAY 0.489362 (-6490 1410);
PAINT MONO (-6490 1410);
FORCEPROP 0 LASTPIN (-6500 1350) $PN T17
J 0
(-6490 1360);
DISPLAY 0.489362 (-6490 1360);
PAINT MONO (-6490 1360);
FORCEPROP 0 LASTPIN (-6500 1300) $PN T19
J 0
(-6490 1310);
DISPLAY 0.489362 (-6490 1310);
PAINT MONO (-6490 1310);
FORCEPROP 0 LASTPIN (-6500 1250) $PN T22
J 0
(-6490 1260);
DISPLAY 0.489362 (-6490 1260);
PAINT MONO (-6490 1260);
FORCEPROP 0 LASTPIN (-6500 1200) $PN T25
J 0
(-6490 1210);
DISPLAY 0.489362 (-6490 1210);
PAINT MONO (-6490 1210);
FORCEPROP 0 LASTPIN (-6500 1150) $PN T28
J 0
(-6490 1160);
DISPLAY 0.489362 (-6490 1160);
PAINT MONO (-6490 1160);
FORCEPROP 0 LASTPIN (-6500 1100) $PN T31
J 0
(-6490 1110);
DISPLAY 0.489362 (-6490 1110);
PAINT MONO (-6490 1110);
FORCEPROP 0 LASTPIN (-6500 1050) $PN T34
J 0
(-6490 1060);
DISPLAY 0.489362 (-6490 1060);
PAINT MONO (-6490 1060);
FORCEPROP 0 LASTPIN (-6500 1000) $PN T37
J 0
(-6490 1010);
DISPLAY 0.489362 (-6490 1010);
PAINT MONO (-6490 1010);
FORCEPROP 0 LASTPIN (-6500 950) $PN T39
J 0
(-6490 960);
DISPLAY 0.489362 (-6490 960);
PAINT MONO (-6490 960);
FORCEPROP 0 LASTPIN (-6500 900) $PN T42
J 0
(-6490 910);
DISPLAY 0.489362 (-6490 910);
PAINT MONO (-6490 910);
FORCEPROP 0 LASTPIN (-6500 850) $PN T45
J 0
(-6490 860);
DISPLAY 0.489362 (-6490 860);
PAINT MONO (-6490 860);
FORCEPROP 0 LASTPIN (-6500 800) $PN T48
J 0
(-6490 810);
DISPLAY 0.489362 (-6490 810);
PAINT MONO (-6490 810);
FORCEPROP 0 LASTPIN (-6500 750) $PN T51
J 0
(-6490 760);
DISPLAY 0.489362 (-6490 760);
PAINT MONO (-6490 760);
FORCEPROP 0 LASTPIN (-6500 700) $PN T54
J 0
(-6490 710);
DISPLAY 0.489362 (-6490 710);
PAINT MONO (-6490 710);
FORCEPROP 0 LASTPIN (-6500 650) $PN T57
J 0
(-6490 660);
DISPLAY 0.489362 (-6490 660);
PAINT MONO (-6490 660);
FORCEPROP 0 LASTPIN (-6500 600) $PN T59
J 0
(-6490 610);
DISPLAY 0.489362 (-6490 610);
PAINT MONO (-6490 610);
FORCEPROP 0 LASTPIN (-6500 550) $PN T61
J 0
(-6490 560);
DISPLAY 0.489362 (-6490 560);
PAINT MONO (-6490 560);
FORCEPROP 0 LASTPIN (-6500 500) $PN T64
J 0
(-6490 510);
DISPLAY 0.489362 (-6490 510);
PAINT MONO (-6490 510);
FORCEPROP 2 LAST PART_TYPE SMLF
J 0
(-7450 6700);
DISPLAY 1.021277 (-7450 6700);
FORCEPROP 1 LAST MATERIAL IO
J 0
(-7445 6532);
DISPLAY 0.489362 (-7445 6532);
PAINT SKYBLUE (-7445 6532);
FORCEPROP 2 LAST VALUE SOCKET6096_13568-001
J 0
(-7450 6575);
DISPLAY 0.489362 (-7450 6575);
PAINT SKYBLUE (-7450 6575);
FORCEPROP 1 LAST PART_NUMBER DGA^6000030
J 0
(-7445 6659);
DISPLAY 0.489362 (-7445 6659);
PAINT SKYBLUE (-7445 6659);
FORCEPROP 2 LAST CDS_LIB pure_quanta
J 0
(-7050 3450);
DISPLAY INVISIBLE (-7050 3450);
FORCEPROP 1 LAST CDS_LMAN_SYM_OUTLINE -400,3050,400,-3050
J 0
(-7050 3450);
DISPLAY 0.468085 (-7050 3450);
PAINT GREEN (-7050 3450);
DISPLAY INVISIBLE (-7050 3450);
FORCEPROP 1 LAST NEEDS_NO_SIZE TRUE
J 0
(-7050 3450);
DISPLAY 0.723404 (-7050 3450);
PAINT GREEN (-7050 3450);
DISPLAY INVISIBLE (-7050 3450);
FORCEPROP 1 LAST PATH I15
J 0
(-7050 3450);
DISPLAY 0.723404 (-7050 3450);
PAINT GREEN (-7050 3450);
DISPLAY INVISIBLE (-7050 3450);
FORCEADD UNIVERSAL_GND..1
(-9250 375);
FORCEPROP 3 LASTPIN (-9250 425) SIG_NAME GND\g
J 0
(-9240 435);
DISPLAY 0.659574 (-9240 435);
PAINT MONO (-9240 435);
DISPLAY INVISIBLE (-9240 435);
FORCEPROP 2 LAST CDS_LIB pure_quanta_power
J 0
(-9250 375);
DISPLAY INVISIBLE (-9250 375);
FORCEPROP 1 LAST PATH I18
J 0
(-9175 375);
DISPLAY 0.872340 (-9175 375);
PAINT AQUA (-9175 375);
DISPLAY INVISIBLE (-9175 375);
FORCEPROP 1 LAST HDL_POWER GND
J 1
(-9225 300);
DISPLAY 0.872340 (-9225 300);
PAINT GREEN (-9225 300);
DISPLAY INVISIBLE (-9225 300);
FORCEADD UNIVERSAL_GND..1
(-7900 400);
FORCEPROP 3 LASTPIN (-7900 450) SIG_NAME GND\g
J 0
(-7890 460);
DISPLAY 0.659574 (-7890 460);
PAINT MONO (-7890 460);
DISPLAY INVISIBLE (-7890 460);
FORCEPROP 2 LAST CDS_LIB pure_quanta_power
J 0
(-7900 400);
DISPLAY INVISIBLE (-7900 400);
FORCEPROP 1 LAST PATH I19
J 0
(-7825 400);
DISPLAY 0.872340 (-7825 400);
PAINT AQUA (-7825 400);
DISPLAY INVISIBLE (-7825 400);
FORCEPROP 1 LAST HDL_POWER GND
J 1
(-7875 325);
DISPLAY 0.872340 (-7875 325);
PAINT GREEN (-7875 325);
DISPLAY INVISIBLE (-7875 325);
FORCEADD UNIVERSAL_GND..1
(-7725 400);
FORCEPROP 3 LASTPIN (-7725 450) SIG_NAME GND\g
J 0
(-7715 460);
DISPLAY 0.659574 (-7715 460);
PAINT MONO (-7715 460);
DISPLAY INVISIBLE (-7715 460);
FORCEPROP 2 LAST CDS_LIB pure_quanta_power
J 0
(-7725 400);
DISPLAY INVISIBLE (-7725 400);
FORCEPROP 1 LAST PATH I20
J 0
(-7650 400);
DISPLAY 0.872340 (-7650 400);
PAINT AQUA (-7650 400);
DISPLAY INVISIBLE (-7650 400);
FORCEPROP 1 LAST HDL_POWER GND
J 1
(-7700 325);
DISPLAY 0.872340 (-7700 325);
PAINT GREEN (-7700 325);
DISPLAY INVISIBLE (-7700 325);
FORCEADD UNIVERSAL_GND..1
(-6375 425);
FORCEPROP 3 LASTPIN (-6375 475) SIG_NAME GND\g
J 0
(-6365 485);
DISPLAY 0.659574 (-6365 485);
PAINT MONO (-6365 485);
DISPLAY INVISIBLE (-6365 485);
FORCEPROP 2 LAST CDS_LIB pure_quanta_power
J 0
(-6375 425);
DISPLAY INVISIBLE (-6375 425);
FORCEPROP 1 LAST PATH I21
J 0
(-6300 425);
DISPLAY 0.872340 (-6300 425);
PAINT AQUA (-6300 425);
DISPLAY INVISIBLE (-6300 425);
FORCEPROP 1 LAST HDL_POWER GND
J 1
(-6350 350);
DISPLAY 0.872340 (-6350 350);
PAINT GREEN (-6350 350);
DISPLAY INVISIBLE (-6350 350);
FORCEADD UNIVERSAL_GND..1
(-6250 425);
FORCEPROP 3 LASTPIN (-6250 475) SIG_NAME GND\g
J 0
(-6240 485);
DISPLAY 0.659574 (-6240 485);
PAINT MONO (-6240 485);
DISPLAY INVISIBLE (-6240 485);
FORCEPROP 2 LAST CDS_LIB pure_quanta_power
J 0
(-6250 425);
DISPLAY INVISIBLE (-6250 425);
FORCEPROP 1 LAST PATH I22
J 0
(-6175 425);
DISPLAY 0.872340 (-6175 425);
PAINT AQUA (-6175 425);
DISPLAY INVISIBLE (-6175 425);
FORCEPROP 1 LAST HDL_POWER GND
J 1
(-6225 350);
DISPLAY 0.872340 (-6225 350);
PAINT GREEN (-6225 350);
DISPLAY INVISIBLE (-6225 350);
FORCEADD UNIVERSAL_GND..1
(-4900 500);
FORCEPROP 3 LASTPIN (-4900 550) SIG_NAME GND\g
J 0
(-4890 560);
DISPLAY 0.659574 (-4890 560);
PAINT MONO (-4890 560);
DISPLAY INVISIBLE (-4890 560);
FORCEPROP 2 LAST CDS_LIB pure_quanta_power
J 0
(-4900 500);
DISPLAY INVISIBLE (-4900 500);
FORCEPROP 1 LAST PATH I23
J 0
(-4825 500);
DISPLAY 0.872340 (-4825 500);
PAINT AQUA (-4825 500);
DISPLAY INVISIBLE (-4825 500);
FORCEPROP 1 LAST HDL_POWER GND
J 1
(-4875 425);
DISPLAY 0.872340 (-4875 425);
PAINT GREEN (-4875 425);
DISPLAY INVISIBLE (-4875 425);
FORCEADD UNIVERSAL_GND..1
(-4750 500);
FORCEPROP 3 LASTPIN (-4750 550) SIG_NAME GND\g
J 0
(-4740 560);
DISPLAY 0.659574 (-4740 560);
PAINT MONO (-4740 560);
DISPLAY INVISIBLE (-4740 560);
FORCEPROP 2 LAST CDS_LIB pure_quanta_power
J 0
(-4750 500);
DISPLAY INVISIBLE (-4750 500);
FORCEPROP 1 LAST PATH I24
J 0
(-4675 500);
DISPLAY 0.872340 (-4675 500);
PAINT AQUA (-4675 500);
DISPLAY INVISIBLE (-4675 500);
FORCEPROP 1 LAST HDL_POWER GND
J 1
(-4725 425);
DISPLAY 0.872340 (-4725 425);
PAINT GREEN (-4725 425);
DISPLAY INVISIBLE (-4725 425);
FORCEADD UNIVERSAL_GND..1
(-3400 525);
FORCEPROP 3 LASTPIN (-3400 575) SIG_NAME GND\g
J 0
(-3390 585);
DISPLAY 0.659574 (-3390 585);
PAINT MONO (-3390 585);
DISPLAY INVISIBLE (-3390 585);
FORCEPROP 2 LAST CDS_LIB pure_quanta_power
J 0
(-3400 525);
DISPLAY INVISIBLE (-3400 525);
FORCEPROP 1 LAST PATH I25
J 0
(-3325 525);
DISPLAY 0.872340 (-3325 525);
PAINT AQUA (-3325 525);
DISPLAY INVISIBLE (-3325 525);
FORCEPROP 1 LAST HDL_POWER GND
J 1
(-3375 450);
DISPLAY 0.872340 (-3375 450);
PAINT GREEN (-3375 450);
DISPLAY INVISIBLE (-3375 450);
FORCEADD UNIVERSAL_GND..1
(-3250 450);
FORCEPROP 3 LASTPIN (-3250 500) SIG_NAME GND\g
J 0
(-3240 510);
DISPLAY 0.659574 (-3240 510);
PAINT MONO (-3240 510);
DISPLAY INVISIBLE (-3240 510);
FORCEPROP 2 LAST CDS_LIB pure_quanta_power
J 0
(-3250 450);
DISPLAY INVISIBLE (-3250 450);
FORCEPROP 1 LAST PATH I26
J 0
(-3175 450);
DISPLAY 0.872340 (-3175 450);
PAINT AQUA (-3175 450);
DISPLAY INVISIBLE (-3175 450);
FORCEPROP 1 LAST HDL_POWER GND
J 1
(-3225 375);
DISPLAY 0.872340 (-3225 375);
PAINT GREEN (-3225 375);
DISPLAY INVISIBLE (-3225 375);
FORCEADD UNIVERSAL_GND..1
(-1925 475);
FORCEPROP 3 LASTPIN (-1925 525) SIG_NAME GND\g
J 0
(-1915 535);
DISPLAY 0.659574 (-1915 535);
PAINT MONO (-1915 535);
DISPLAY INVISIBLE (-1915 535);
FORCEPROP 2 LAST CDS_LIB pure_quanta_power
J 0
(-1925 475);
DISPLAY INVISIBLE (-1925 475);
FORCEPROP 1 LAST PATH I27
J 0
(-1850 475);
DISPLAY 0.872340 (-1850 475);
PAINT AQUA (-1850 475);
DISPLAY INVISIBLE (-1850 475);
FORCEPROP 1 LAST HDL_POWER GND
J 1
(-1900 400);
DISPLAY 0.872340 (-1900 400);
PAINT GREEN (-1900 400);
DISPLAY INVISIBLE (-1900 400);
FORCEADD UNIVERSAL_GND..1
(-1625 450);
FORCEPROP 3 LASTPIN (-1625 500) SIG_NAME GND\g
J 0
(-1615 510);
DISPLAY 0.659574 (-1615 510);
PAINT MONO (-1615 510);
DISPLAY INVISIBLE (-1615 510);
FORCEPROP 2 LAST CDS_LIB pure_quanta_power
J 0
(-1625 450);
DISPLAY INVISIBLE (-1625 450);
FORCEPROP 1 LAST PATH I28
J 0
(-1550 450);
DISPLAY 0.872340 (-1550 450);
PAINT AQUA (-1550 450);
DISPLAY INVISIBLE (-1550 450);
FORCEPROP 1 LAST HDL_POWER GND
J 1
(-1600 375);
DISPLAY 0.872340 (-1600 375);
PAINT GREEN (-1600 375);
DISPLAY INVISIBLE (-1600 375);
FORCEADD UNIVERSAL_GND..1
(-300 475);
FORCEPROP 3 LASTPIN (-300 525) SIG_NAME GND\g
J 0
(-290 535);
DISPLAY 0.659574 (-290 535);
PAINT MONO (-290 535);
DISPLAY INVISIBLE (-290 535);
FORCEPROP 2 LAST CDS_LIB pure_quanta_power
J 0
(-300 475);
DISPLAY INVISIBLE (-300 475);
FORCEPROP 1 LAST PATH I29
J 0
(-225 475);
DISPLAY 0.872340 (-225 475);
PAINT AQUA (-225 475);
DISPLAY INVISIBLE (-225 475);
FORCEPROP 1 LAST HDL_POWER GND
J 1
(-275 400);
DISPLAY 0.872340 (-275 400);
PAINT GREEN (-275 400);
DISPLAY INVISIBLE (-275 400);
FORCEADD GENOA_SP5..33
(-975 3500);
FORCEPROP 1 LAST LOCATION U26
J 0
(-1375 6650);
DISPLAY 0.489362 (-1375 6650);
PAINT SKYBLUE (-1375 6650);
FORCEPROP 0 LAST $SEC 33
J 0
(-1350 6900);
DISPLAY 0.680851 (-1350 6900);
PAINT MONO (-1350 6900);
DISPLAY INVISIBLE (-1350 6900);
FORCEPROP 0 LAST CDS_SEC 33
J 0
(-1350 6900);
DISPLAY 1.021277 (-1350 6900);
DISPLAY INVISIBLE (-1350 6900);
FORCEPROP 0 LASTPIN (-1525 6450) $PN AW63
J 2
(-1510 6460);
DISPLAY 0.489362 (-1510 6460);
PAINT MONO (-1510 6460);
FORCEPROP 0 LASTPIN (-1525 6400) $PN AW65
J 2
(-1510 6410);
DISPLAY 0.489362 (-1510 6410);
PAINT MONO (-1510 6410);
FORCEPROP 0 LASTPIN (-1525 6350) $PN AW68
J 2
(-1510 6360);
DISPLAY 0.489362 (-1510 6360);
PAINT MONO (-1510 6360);
FORCEPROP 0 LASTPIN (-1525 6300) $PN AW70
J 2
(-1510 6310);
DISPLAY 0.489362 (-1510 6310);
PAINT MONO (-1510 6310);
FORCEPROP 0 LASTPIN (-1525 6250) $PN AW72
J 2
(-1510 6260);
DISPLAY 0.489362 (-1510 6260);
PAINT MONO (-1510 6260);
FORCEPROP 0 LASTPIN (-1525 6200) $PN AW75
J 2
(-1510 6210);
DISPLAY 0.489362 (-1510 6210);
PAINT MONO (-1510 6210);
FORCEPROP 0 LASTPIN (-1525 6150) $PN AY3
J 2
(-1510 6160);
DISPLAY 0.489362 (-1510 6160);
PAINT MONO (-1510 6160);
FORCEPROP 0 LASTPIN (-1525 6100) $PN AY5
J 2
(-1510 6110);
DISPLAY 0.489362 (-1510 6110);
PAINT MONO (-1510 6110);
FORCEPROP 0 LASTPIN (-1525 6050) $PN AY8
J 2
(-1510 6060);
DISPLAY 0.489362 (-1510 6060);
PAINT MONO (-1510 6060);
FORCEPROP 0 LASTPIN (-1525 6000) $PN AY10
J 2
(-1510 6010);
DISPLAY 0.489362 (-1510 6010);
PAINT MONO (-1510 6010);
FORCEPROP 0 LASTPIN (-1525 5950) $PN AY12
J 2
(-1510 5960);
DISPLAY 0.489362 (-1510 5960);
PAINT MONO (-1510 5960);
FORCEPROP 0 LASTPIN (-1525 5900) $PN AY15
J 2
(-1510 5910);
DISPLAY 0.489362 (-1510 5910);
PAINT MONO (-1510 5910);
FORCEPROP 0 LASTPIN (-1525 5850) $PN AY17
J 2
(-1510 5860);
DISPLAY 0.489362 (-1510 5860);
PAINT MONO (-1510 5860);
FORCEPROP 0 LASTPIN (-1525 5800) $PN AY19
J 2
(-1510 5810);
DISPLAY 0.489362 (-1510 5810);
PAINT MONO (-1510 5810);
FORCEPROP 0 LASTPIN (-1525 5750) $PN AY23
J 2
(-1510 5760);
DISPLAY 0.489362 (-1510 5760);
PAINT MONO (-1510 5760);
FORCEPROP 0 LASTPIN (-1525 5700) $PN AY25
J 2
(-1510 5710);
DISPLAY 0.489362 (-1510 5710);
PAINT MONO (-1510 5710);
FORCEPROP 0 LASTPIN (-1525 5650) $PN AY27
J 2
(-1510 5660);
DISPLAY 0.489362 (-1510 5660);
PAINT MONO (-1510 5660);
FORCEPROP 0 LASTPIN (-1525 5600) $PN AY48
J 2
(-1510 5610);
DISPLAY 0.489362 (-1510 5610);
PAINT MONO (-1510 5610);
FORCEPROP 0 LASTPIN (-1525 5550) $PN AY50
J 2
(-1510 5560);
DISPLAY 0.489362 (-1510 5560);
PAINT MONO (-1510 5560);
FORCEPROP 0 LASTPIN (-1525 5500) $PN AY52
J 2
(-1510 5510);
DISPLAY 0.489362 (-1510 5510);
PAINT MONO (-1510 5510);
FORCEPROP 0 LASTPIN (-1525 5450) $PN AY54
J 2
(-1510 5460);
DISPLAY 0.489362 (-1510 5460);
PAINT MONO (-1510 5460);
FORCEPROP 0 LASTPIN (-1525 5400) $PN AY57
J 2
(-1510 5410);
DISPLAY 0.489362 (-1510 5410);
PAINT MONO (-1510 5410);
FORCEPROP 0 LASTPIN (-1525 5350) $PN AY59
J 2
(-1510 5360);
DISPLAY 0.489362 (-1510 5360);
PAINT MONO (-1510 5360);
FORCEPROP 0 LASTPIN (-1525 5300) $PN AY61
J 2
(-1510 5310);
DISPLAY 0.489362 (-1510 5310);
PAINT MONO (-1510 5310);
FORCEPROP 0 LASTPIN (-1525 5250) $PN AY64
J 2
(-1510 5260);
DISPLAY 0.489362 (-1510 5260);
PAINT MONO (-1510 5260);
FORCEPROP 0 LASTPIN (-1525 5200) $PN AY66
J 2
(-1510 5210);
DISPLAY 0.489362 (-1510 5210);
PAINT MONO (-1510 5210);
FORCEPROP 0 LASTPIN (-1525 5150) $PN AY68
J 2
(-1510 5160);
DISPLAY 0.489362 (-1510 5160);
PAINT MONO (-1510 5160);
FORCEPROP 0 LASTPIN (-1525 5100) $PN AY71
J 2
(-1510 5110);
DISPLAY 0.489362 (-1510 5110);
PAINT MONO (-1510 5110);
FORCEPROP 0 LASTPIN (-1525 5050) $PN AY73
J 2
(-1510 5060);
DISPLAY 0.489362 (-1510 5060);
PAINT MONO (-1510 5060);
FORCEPROP 0 LASTPIN (-1525 5000) $PN BA1
J 2
(-1510 5010);
DISPLAY 0.489362 (-1510 5010);
PAINT MONO (-1510 5010);
FORCEPROP 0 LASTPIN (-1525 4950) $PN BA6
J 2
(-1510 4960);
DISPLAY 0.489362 (-1510 4960);
PAINT MONO (-1510 4960);
FORCEPROP 0 LASTPIN (-1525 4900) $PN BA8
J 2
(-1510 4910);
DISPLAY 0.489362 (-1510 4910);
PAINT MONO (-1510 4910);
FORCEPROP 0 LASTPIN (-1525 4850) $PN BA13
J 2
(-1510 4860);
DISPLAY 0.489362 (-1510 4860);
PAINT MONO (-1510 4860);
FORCEPROP 0 LASTPIN (-1525 4800) $PN BA15
J 2
(-1510 4810);
DISPLAY 0.489362 (-1510 4810);
PAINT MONO (-1510 4810);
FORCEPROP 0 LASTPIN (-1525 4750) $PN BA20
J 2
(-1510 4760);
DISPLAY 0.489362 (-1510 4760);
PAINT MONO (-1510 4760);
FORCEPROP 0 LASTPIN (-1525 4700) $PN BA22
J 2
(-1510 4710);
DISPLAY 0.489362 (-1510 4710);
PAINT MONO (-1510 4710);
FORCEPROP 0 LASTPIN (-1525 4650) $PN BA24
J 2
(-1510 4660);
DISPLAY 0.489362 (-1510 4660);
PAINT MONO (-1510 4660);
FORCEPROP 0 LASTPIN (-1525 4600) $PN BA26
J 2
(-1510 4610);
DISPLAY 0.489362 (-1510 4610);
PAINT MONO (-1510 4610);
FORCEPROP 0 LASTPIN (-1525 4550) $PN BA28
J 2
(-1510 4560);
DISPLAY 0.489362 (-1510 4560);
PAINT MONO (-1510 4560);
FORCEPROP 0 LASTPIN (-1525 4500) $PN BA49
J 2
(-1510 4510);
DISPLAY 0.489362 (-1510 4510);
PAINT MONO (-1510 4510);
FORCEPROP 0 LASTPIN (-1525 4450) $PN BA51
J 2
(-1510 4460);
DISPLAY 0.489362 (-1510 4460);
PAINT MONO (-1510 4460);
FORCEPROP 0 LASTPIN (-1525 4400) $PN BA53
J 2
(-1510 4410);
DISPLAY 0.489362 (-1510 4410);
PAINT MONO (-1510 4410);
FORCEPROP 0 LASTPIN (-1525 4350) $PN BA56
J 2
(-1510 4360);
DISPLAY 0.489362 (-1510 4360);
PAINT MONO (-1510 4360);
FORCEPROP 0 LASTPIN (-1525 4300) $PN BA61
J 2
(-1510 4310);
DISPLAY 0.489362 (-1510 4310);
PAINT MONO (-1510 4310);
FORCEPROP 0 LASTPIN (-1525 4250) $PN BA63
J 2
(-1510 4260);
DISPLAY 0.489362 (-1510 4260);
PAINT MONO (-1510 4260);
FORCEPROP 0 LASTPIN (-1525 4200) $PN BA68
J 2
(-1510 4210);
DISPLAY 0.489362 (-1510 4210);
PAINT MONO (-1510 4210);
FORCEPROP 0 LASTPIN (-1525 4150) $PN BA70
J 2
(-1510 4160);
DISPLAY 0.489362 (-1510 4160);
PAINT MONO (-1510 4160);
FORCEPROP 0 LASTPIN (-1525 4100) $PN BA75
J 2
(-1510 4110);
DISPLAY 0.489362 (-1510 4110);
PAINT MONO (-1510 4110);
FORCEPROP 0 LASTPIN (-1525 4050) $PN BB3
J 2
(-1510 4060);
DISPLAY 0.489362 (-1510 4060);
PAINT MONO (-1510 4060);
FORCEPROP 0 LASTPIN (-1525 4000) $PN BB5
J 2
(-1510 4010);
DISPLAY 0.489362 (-1510 4010);
PAINT MONO (-1510 4010);
FORCEPROP 0 LASTPIN (-1525 3950) $PN BB8
J 2
(-1510 3960);
DISPLAY 0.489362 (-1510 3960);
PAINT MONO (-1510 3960);
FORCEPROP 0 LASTPIN (-1525 3900) $PN BB10
J 2
(-1510 3910);
DISPLAY 0.489362 (-1510 3910);
PAINT MONO (-1510 3910);
FORCEPROP 0 LASTPIN (-1525 3850) $PN BB12
J 2
(-1510 3860);
DISPLAY 0.489362 (-1510 3860);
PAINT MONO (-1510 3860);
FORCEPROP 0 LASTPIN (-1525 3800) $PN BB15
J 2
(-1510 3810);
DISPLAY 0.489362 (-1510 3810);
PAINT MONO (-1510 3810);
FORCEPROP 0 LASTPIN (-1525 3750) $PN BB17
J 2
(-1510 3760);
DISPLAY 0.489362 (-1510 3760);
PAINT MONO (-1510 3760);
FORCEPROP 0 LASTPIN (-1525 3700) $PN BB19
J 2
(-1510 3710);
DISPLAY 0.489362 (-1510 3710);
PAINT MONO (-1510 3710);
FORCEPROP 0 LASTPIN (-1525 3650) $PN BB23
J 2
(-1510 3660);
DISPLAY 0.489362 (-1510 3660);
PAINT MONO (-1510 3660);
FORCEPROP 0 LASTPIN (-1525 3600) $PN BB25
J 2
(-1510 3610);
DISPLAY 0.489362 (-1510 3610);
PAINT MONO (-1510 3610);
FORCEPROP 0 LASTPIN (-1525 3550) $PN BB27
J 2
(-1510 3560);
DISPLAY 0.489362 (-1510 3560);
PAINT MONO (-1510 3560);
FORCEPROP 0 LASTPIN (-1525 3500) $PN BB48
J 2
(-1510 3510);
DISPLAY 0.489362 (-1510 3510);
PAINT MONO (-1510 3510);
FORCEPROP 0 LASTPIN (-1525 3450) $PN BB50
J 2
(-1510 3460);
DISPLAY 0.489362 (-1510 3460);
PAINT MONO (-1510 3460);
FORCEPROP 0 LASTPIN (-1525 3400) $PN BB52
J 2
(-1510 3410);
DISPLAY 0.489362 (-1510 3410);
PAINT MONO (-1510 3410);
FORCEPROP 0 LASTPIN (-1525 3350) $PN BB54
J 2
(-1510 3360);
DISPLAY 0.489362 (-1510 3360);
PAINT MONO (-1510 3360);
FORCEPROP 0 LASTPIN (-1525 3300) $PN BB57
J 2
(-1510 3310);
DISPLAY 0.489362 (-1510 3310);
PAINT MONO (-1510 3310);
FORCEPROP 0 LASTPIN (-1525 3250) $PN BB59
J 2
(-1510 3260);
DISPLAY 0.489362 (-1510 3260);
PAINT MONO (-1510 3260);
FORCEPROP 0 LASTPIN (-1525 3200) $PN BB61
J 2
(-1510 3210);
DISPLAY 0.489362 (-1510 3210);
PAINT MONO (-1510 3210);
FORCEPROP 0 LASTPIN (-1525 3150) $PN BB64
J 2
(-1510 3160);
DISPLAY 0.489362 (-1510 3160);
PAINT MONO (-1510 3160);
FORCEPROP 0 LASTPIN (-1525 3100) $PN BB66
J 2
(-1510 3110);
DISPLAY 0.489362 (-1510 3110);
PAINT MONO (-1510 3110);
FORCEPROP 0 LASTPIN (-1525 3050) $PN BB68
J 2
(-1510 3060);
DISPLAY 0.489362 (-1510 3060);
PAINT MONO (-1510 3060);
FORCEPROP 0 LASTPIN (-1525 3000) $PN BB71
J 2
(-1510 3010);
DISPLAY 0.489362 (-1510 3010);
PAINT MONO (-1510 3010);
FORCEPROP 0 LASTPIN (-1525 2950) $PN BB73
J 2
(-1510 2960);
DISPLAY 0.489362 (-1510 2960);
PAINT MONO (-1510 2960);
FORCEPROP 0 LASTPIN (-1525 2900) $PN BC1
J 2
(-1510 2910);
DISPLAY 0.489362 (-1510 2910);
PAINT MONO (-1510 2910);
FORCEPROP 0 LASTPIN (-1525 2850) $PN BC4
J 2
(-1510 2860);
DISPLAY 0.489362 (-1510 2860);
PAINT MONO (-1510 2860);
FORCEPROP 0 LASTPIN (-1525 2800) $PN BC6
J 2
(-1510 2810);
DISPLAY 0.489362 (-1510 2810);
PAINT MONO (-1510 2810);
FORCEPROP 0 LASTPIN (-1525 2750) $PN BC8
J 2
(-1510 2760);
DISPLAY 0.489362 (-1510 2760);
PAINT MONO (-1510 2760);
FORCEPROP 0 LASTPIN (-1525 2700) $PN BC11
J 2
(-1510 2710);
DISPLAY 0.489362 (-1510 2710);
PAINT MONO (-1510 2710);
FORCEPROP 0 LASTPIN (-1525 2650) $PN BC13
J 2
(-1510 2660);
DISPLAY 0.489362 (-1510 2660);
PAINT MONO (-1510 2660);
FORCEPROP 0 LASTPIN (-1525 2600) $PN BC15
J 2
(-1510 2610);
DISPLAY 0.489362 (-1510 2610);
PAINT MONO (-1510 2610);
FORCEPROP 0 LASTPIN (-1525 2550) $PN BC18
J 2
(-1510 2560);
DISPLAY 0.489362 (-1510 2560);
PAINT MONO (-1510 2560);
FORCEPROP 0 LASTPIN (-1525 2500) $PN BC20
J 2
(-1510 2510);
DISPLAY 0.489362 (-1510 2510);
PAINT MONO (-1510 2510);
FORCEPROP 0 LASTPIN (-1525 2450) $PN BC22
J 2
(-1510 2460);
DISPLAY 0.489362 (-1510 2460);
PAINT MONO (-1510 2460);
FORCEPROP 0 LASTPIN (-1525 2400) $PN BC24
J 2
(-1510 2410);
DISPLAY 0.489362 (-1510 2410);
PAINT MONO (-1510 2410);
FORCEPROP 0 LASTPIN (-1525 2350) $PN BC26
J 2
(-1510 2360);
DISPLAY 0.489362 (-1510 2360);
PAINT MONO (-1510 2360);
FORCEPROP 0 LASTPIN (-1525 2300) $PN BC28
J 2
(-1510 2310);
DISPLAY 0.489362 (-1510 2310);
PAINT MONO (-1510 2310);
FORCEPROP 0 LASTPIN (-1525 2250) $PN BC49
J 2
(-1510 2260);
DISPLAY 0.489362 (-1510 2260);
PAINT MONO (-1510 2260);
FORCEPROP 0 LASTPIN (-1525 2200) $PN BC50
J 2
(-1510 2210);
DISPLAY 0.489362 (-1510 2210);
PAINT MONO (-1510 2210);
FORCEPROP 0 LASTPIN (-1525 2150) $PN BC51
J 2
(-1510 2160);
DISPLAY 0.489362 (-1510 2160);
PAINT MONO (-1510 2160);
FORCEPROP 0 LASTPIN (-1525 2100) $PN BC53
J 2
(-1510 2110);
DISPLAY 0.489362 (-1510 2110);
PAINT MONO (-1510 2110);
FORCEPROP 0 LASTPIN (-1525 2050) $PN BC56
J 2
(-1510 2060);
DISPLAY 0.489362 (-1510 2060);
PAINT MONO (-1510 2060);
FORCEPROP 0 LASTPIN (-1525 2000) $PN BC58
J 2
(-1510 2010);
DISPLAY 0.489362 (-1510 2010);
PAINT MONO (-1510 2010);
FORCEPROP 0 LASTPIN (-1525 1950) $PN BC61
J 2
(-1510 1960);
DISPLAY 0.489362 (-1510 1960);
PAINT MONO (-1510 1960);
FORCEPROP 0 LASTPIN (-1525 1900) $PN BC63
J 2
(-1510 1910);
DISPLAY 0.489362 (-1510 1910);
PAINT MONO (-1510 1910);
FORCEPROP 0 LASTPIN (-1525 1850) $PN BC65
J 2
(-1510 1860);
DISPLAY 0.489362 (-1510 1860);
PAINT MONO (-1510 1860);
FORCEPROP 0 LASTPIN (-1525 1800) $PN BC68
J 2
(-1510 1810);
DISPLAY 0.489362 (-1510 1810);
PAINT MONO (-1510 1810);
FORCEPROP 0 LASTPIN (-1525 1750) $PN BC70
J 2
(-1510 1760);
DISPLAY 0.489362 (-1510 1760);
PAINT MONO (-1510 1760);
FORCEPROP 0 LASTPIN (-1525 1700) $PN BC72
J 2
(-1510 1710);
DISPLAY 0.489362 (-1510 1710);
PAINT MONO (-1510 1710);
FORCEPROP 0 LASTPIN (-1525 1650) $PN BC75
J 2
(-1510 1660);
DISPLAY 0.489362 (-1510 1660);
PAINT MONO (-1510 1660);
FORCEPROP 0 LASTPIN (-1525 1600) $PN BD3
J 2
(-1510 1610);
DISPLAY 0.489362 (-1510 1610);
PAINT MONO (-1510 1610);
FORCEPROP 0 LASTPIN (-1525 1550) $PN BD8
J 2
(-1510 1560);
DISPLAY 0.489362 (-1510 1560);
PAINT MONO (-1510 1560);
FORCEPROP 0 LASTPIN (-1525 1500) $PN BD10
J 2
(-1510 1510);
DISPLAY 0.489362 (-1510 1510);
PAINT MONO (-1510 1510);
FORCEPROP 0 LASTPIN (-1525 1450) $PN BD15
J 2
(-1510 1460);
DISPLAY 0.489362 (-1510 1460);
PAINT MONO (-1510 1460);
FORCEPROP 0 LASTPIN (-1525 1400) $PN BD17
J 2
(-1510 1410);
DISPLAY 0.489362 (-1510 1410);
PAINT MONO (-1510 1410);
FORCEPROP 0 LASTPIN (-1525 1350) $PN BD23
J 2
(-1510 1360);
DISPLAY 0.489362 (-1510 1360);
PAINT MONO (-1510 1360);
FORCEPROP 0 LASTPIN (-1525 1300) $PN BD25
J 2
(-1510 1310);
DISPLAY 0.489362 (-1510 1310);
PAINT MONO (-1510 1310);
FORCEPROP 0 LASTPIN (-1525 1250) $PN BD27
J 2
(-1510 1260);
DISPLAY 0.489362 (-1510 1260);
PAINT MONO (-1510 1260);
FORCEPROP 0 LASTPIN (-1525 1200) $PN BD49
J 2
(-1510 1210);
DISPLAY 0.489362 (-1510 1210);
PAINT MONO (-1510 1210);
FORCEPROP 0 LASTPIN (-1525 1150) $PN BD51
J 2
(-1510 1160);
DISPLAY 0.489362 (-1510 1160);
PAINT MONO (-1510 1160);
FORCEPROP 0 LASTPIN (-1525 1100) $PN BD53
J 2
(-1510 1110);
DISPLAY 0.489362 (-1510 1110);
PAINT MONO (-1510 1110);
FORCEPROP 0 LASTPIN (-1525 1050) $PN BD57
J 2
(-1510 1060);
DISPLAY 0.489362 (-1510 1060);
PAINT MONO (-1510 1060);
FORCEPROP 0 LASTPIN (-1525 1000) $PN BD59
J 2
(-1510 1010);
DISPLAY 0.489362 (-1510 1010);
PAINT MONO (-1510 1010);
FORCEPROP 0 LASTPIN (-1525 950) $PN BD61
J 2
(-1510 960);
DISPLAY 0.489362 (-1510 960);
PAINT MONO (-1510 960);
FORCEPROP 0 LASTPIN (-1525 900) $PN BD64
J 2
(-1510 910);
DISPLAY 0.489362 (-1510 910);
PAINT MONO (-1510 910);
FORCEPROP 0 LASTPIN (-1525 850) $PN BD66
J 2
(-1510 860);
DISPLAY 0.489362 (-1510 860);
PAINT MONO (-1510 860);
FORCEPROP 0 LASTPIN (-1525 800) $PN BD68
J 2
(-1510 810);
DISPLAY 0.489362 (-1510 810);
PAINT MONO (-1510 810);
FORCEPROP 0 LASTPIN (-1525 750) $PN BD71
J 2
(-1510 760);
DISPLAY 0.489362 (-1510 760);
PAINT MONO (-1510 760);
FORCEPROP 0 LASTPIN (-1525 700) $PN BD73
J 2
(-1510 710);
DISPLAY 0.489362 (-1510 710);
PAINT MONO (-1510 710);
FORCEPROP 0 LASTPIN (-1525 650) $PN BF3
J 2
(-1510 660);
DISPLAY 0.489362 (-1510 660);
PAINT MONO (-1510 660);
FORCEPROP 0 LASTPIN (-1525 600) $PN BF5
J 2
(-1510 610);
DISPLAY 0.489362 (-1510 610);
PAINT MONO (-1510 610);
FORCEPROP 0 LASTPIN (-1525 550) $PN BF8
J 2
(-1510 560);
DISPLAY 0.489362 (-1510 560);
PAINT MONO (-1510 560);
FORCEPROP 0 LASTPIN (-425 6450) $PN BF10
J 0
(-460 6460);
DISPLAY 0.489362 (-460 6460);
PAINT MONO (-460 6460);
FORCEPROP 0 LASTPIN (-425 6400) $PN BF12
J 0
(-460 6410);
DISPLAY 0.489362 (-460 6410);
PAINT MONO (-460 6410);
FORCEPROP 0 LASTPIN (-425 6350) $PN BF15
J 0
(-460 6360);
DISPLAY 0.489362 (-460 6360);
PAINT MONO (-460 6360);
FORCEPROP 0 LASTPIN (-425 6300) $PN BF17
J 0
(-460 6310);
DISPLAY 0.489362 (-460 6310);
PAINT MONO (-460 6310);
FORCEPROP 0 LASTPIN (-425 6250) $PN BF19
J 0
(-460 6260);
DISPLAY 0.489362 (-460 6260);
PAINT MONO (-460 6260);
FORCEPROP 0 LASTPIN (-425 6200) $PN BF22
J 0
(-460 6210);
DISPLAY 0.489362 (-460 6210);
PAINT MONO (-460 6210);
FORCEPROP 0 LASTPIN (-425 6150) $PN BF24
J 0
(-460 6160);
DISPLAY 0.489362 (-460 6160);
PAINT MONO (-460 6160);
FORCEPROP 0 LASTPIN (-425 6100) $PN BF26
J 0
(-460 6110);
DISPLAY 0.489362 (-460 6110);
PAINT MONO (-460 6110);
FORCEPROP 0 LASTPIN (-425 6050) $PN BF28
J 0
(-460 6060);
DISPLAY 0.489362 (-460 6060);
PAINT MONO (-460 6060);
FORCEPROP 0 LASTPIN (-425 6000) $PN BF49
J 0
(-460 6010);
DISPLAY 0.489362 (-460 6010);
PAINT MONO (-460 6010);
FORCEPROP 0 LASTPIN (-425 5950) $PN BF50
J 0
(-460 5960);
DISPLAY 0.489362 (-460 5960);
PAINT MONO (-460 5960);
FORCEPROP 0 LASTPIN (-425 5900) $PN BF52
J 0
(-460 5910);
DISPLAY 0.489362 (-460 5910);
PAINT MONO (-460 5910);
FORCEPROP 0 LASTPIN (-425 5850) $PN BF54
J 0
(-460 5860);
DISPLAY 0.489362 (-460 5860);
PAINT MONO (-460 5860);
FORCEPROP 0 LASTPIN (-425 5800) $PN BF59
J 0
(-460 5810);
DISPLAY 0.489362 (-460 5810);
PAINT MONO (-460 5810);
FORCEPROP 0 LASTPIN (-425 5750) $PN BF61
J 0
(-460 5760);
DISPLAY 0.489362 (-460 5760);
PAINT MONO (-460 5760);
FORCEPROP 0 LASTPIN (-425 5700) $PN BF66
J 0
(-460 5710);
DISPLAY 0.489362 (-460 5710);
PAINT MONO (-460 5710);
FORCEPROP 0 LASTPIN (-425 5650) $PN BF68
J 0
(-460 5660);
DISPLAY 0.489362 (-460 5660);
PAINT MONO (-460 5660);
FORCEPROP 0 LASTPIN (-425 5600) $PN BF73
J 0
(-460 5610);
DISPLAY 0.489362 (-460 5610);
PAINT MONO (-460 5610);
FORCEPROP 0 LASTPIN (-425 5550) $PN BG1
J 0
(-460 5560);
DISPLAY 0.489362 (-460 5560);
PAINT MONO (-460 5560);
FORCEPROP 0 LASTPIN (-425 5500) $PN BG4
J 0
(-460 5510);
DISPLAY 0.489362 (-460 5510);
PAINT MONO (-460 5510);
FORCEPROP 0 LASTPIN (-425 5450) $PN BG6
J 0
(-460 5460);
DISPLAY 0.489362 (-460 5460);
PAINT MONO (-460 5460);
FORCEPROP 0 LASTPIN (-425 5400) $PN BG8
J 0
(-460 5410);
DISPLAY 0.489362 (-460 5410);
PAINT MONO (-460 5410);
FORCEPROP 0 LASTPIN (-425 5350) $PN BG11
J 0
(-460 5360);
DISPLAY 0.489362 (-460 5360);
PAINT MONO (-460 5360);
FORCEPROP 0 LASTPIN (-425 5300) $PN BG13
J 0
(-460 5310);
DISPLAY 0.489362 (-460 5310);
PAINT MONO (-460 5310);
FORCEPROP 0 LASTPIN (-425 5250) $PN BG15
J 0
(-460 5260);
DISPLAY 0.489362 (-460 5260);
PAINT MONO (-460 5260);
FORCEPROP 0 LASTPIN (-425 5200) $PN BG18
J 0
(-460 5210);
DISPLAY 0.489362 (-460 5210);
PAINT MONO (-460 5210);
FORCEPROP 0 LASTPIN (-425 5150) $PN BG20
J 0
(-460 5160);
DISPLAY 0.489362 (-460 5160);
PAINT MONO (-460 5160);
FORCEPROP 0 LASTPIN (-425 5100) $PN BG23
J 0
(-460 5110);
DISPLAY 0.489362 (-460 5110);
PAINT MONO (-460 5110);
FORCEPROP 0 LASTPIN (-425 5050) $PN BG25
J 0
(-460 5060);
DISPLAY 0.489362 (-460 5060);
PAINT MONO (-460 5060);
FORCEPROP 0 LASTPIN (-425 5000) $PN BG27
J 0
(-460 5010);
DISPLAY 0.489362 (-460 5010);
PAINT MONO (-460 5010);
FORCEPROP 0 LASTPIN (-425 4950) $PN BG49
J 0
(-460 4960);
DISPLAY 0.489362 (-460 4960);
PAINT MONO (-460 4960);
FORCEPROP 0 LASTPIN (-425 4900) $PN BG51
J 0
(-460 4910);
DISPLAY 0.489362 (-460 4910);
PAINT MONO (-460 4910);
FORCEPROP 0 LASTPIN (-425 4850) $PN BG53
J 0
(-460 4860);
DISPLAY 0.489362 (-460 4860);
PAINT MONO (-460 4860);
FORCEPROP 0 LASTPIN (-425 4800) $PN BG56
J 0
(-460 4810);
DISPLAY 0.489362 (-460 4810);
PAINT MONO (-460 4810);
FORCEPROP 0 LASTPIN (-425 4750) $PN BG58
J 0
(-460 4760);
DISPLAY 0.489362 (-460 4760);
PAINT MONO (-460 4760);
FORCEPROP 0 LASTPIN (-425 4700) $PN BG61
J 0
(-460 4710);
DISPLAY 0.489362 (-460 4710);
PAINT MONO (-460 4710);
FORCEPROP 0 LASTPIN (-425 4650) $PN BG63
J 0
(-460 4660);
DISPLAY 0.489362 (-460 4660);
PAINT MONO (-460 4660);
FORCEPROP 0 LASTPIN (-425 4600) $PN BG65
J 0
(-460 4610);
DISPLAY 0.489362 (-460 4610);
PAINT MONO (-460 4610);
FORCEPROP 0 LASTPIN (-425 4550) $PN BG68
J 0
(-460 4560);
DISPLAY 0.489362 (-460 4560);
PAINT MONO (-460 4560);
FORCEPROP 0 LASTPIN (-425 4500) $PN BG70
J 0
(-460 4510);
DISPLAY 0.489362 (-460 4510);
PAINT MONO (-460 4510);
FORCEPROP 0 LASTPIN (-425 4450) $PN BG72
J 0
(-460 4460);
DISPLAY 0.489362 (-460 4460);
PAINT MONO (-460 4460);
FORCEPROP 0 LASTPIN (-425 4400) $PN BG75
J 0
(-460 4410);
DISPLAY 0.489362 (-460 4410);
PAINT MONO (-460 4410);
FORCEPROP 0 LASTPIN (-425 4350) $PN BH3
J 0
(-460 4360);
DISPLAY 0.489362 (-460 4360);
PAINT MONO (-460 4360);
FORCEPROP 0 LASTPIN (-425 4300) $PN BH5
J 0
(-460 4310);
DISPLAY 0.489362 (-460 4310);
PAINT MONO (-460 4310);
FORCEPROP 0 LASTPIN (-425 4250) $PN BH8
J 0
(-460 4260);
DISPLAY 0.489362 (-460 4260);
PAINT MONO (-460 4260);
FORCEPROP 0 LASTPIN (-425 4200) $PN BH10
J 0
(-460 4210);
DISPLAY 0.489362 (-460 4210);
PAINT MONO (-460 4210);
FORCEPROP 0 LASTPIN (-425 4150) $PN BH12
J 0
(-460 4160);
DISPLAY 0.489362 (-460 4160);
PAINT MONO (-460 4160);
FORCEPROP 0 LASTPIN (-425 4100) $PN BH15
J 0
(-460 4110);
DISPLAY 0.489362 (-460 4110);
PAINT MONO (-460 4110);
FORCEPROP 0 LASTPIN (-425 4050) $PN BH17
J 0
(-460 4060);
DISPLAY 0.489362 (-460 4060);
PAINT MONO (-460 4060);
FORCEPROP 0 LASTPIN (-425 4000) $PN BH19
J 0
(-460 4010);
DISPLAY 0.489362 (-460 4010);
PAINT MONO (-460 4010);
FORCEPROP 0 LASTPIN (-425 3950) $PN BH22
J 0
(-460 3960);
DISPLAY 0.489362 (-460 3960);
PAINT MONO (-460 3960);
FORCEPROP 0 LASTPIN (-425 3900) $PN BH24
J 0
(-460 3910);
DISPLAY 0.489362 (-460 3910);
PAINT MONO (-460 3910);
FORCEPROP 0 LASTPIN (-425 3850) $PN BH26
J 0
(-460 3860);
DISPLAY 0.489362 (-460 3860);
PAINT MONO (-460 3860);
FORCEPROP 0 LASTPIN (-425 3800) $PN BH28
J 0
(-460 3810);
DISPLAY 0.489362 (-460 3810);
PAINT MONO (-460 3810);
FORCEPROP 0 LASTPIN (-425 3750) $PN BH49
J 0
(-460 3760);
DISPLAY 0.489362 (-460 3760);
PAINT MONO (-460 3760);
FORCEPROP 0 LASTPIN (-425 3700) $PN BH50
J 0
(-460 3710);
DISPLAY 0.489362 (-460 3710);
PAINT MONO (-460 3710);
FORCEPROP 0 LASTPIN (-425 3650) $PN BH52
J 0
(-460 3660);
DISPLAY 0.489362 (-460 3660);
PAINT MONO (-460 3660);
FORCEPROP 0 LASTPIN (-425 3600) $PN BH54
J 0
(-460 3610);
DISPLAY 0.489362 (-460 3610);
PAINT MONO (-460 3610);
FORCEPROP 0 LASTPIN (-425 3550) $PN BH57
J 0
(-460 3560);
DISPLAY 0.489362 (-460 3560);
PAINT MONO (-460 3560);
FORCEPROP 0 LASTPIN (-425 3500) $PN BH59
J 0
(-460 3510);
DISPLAY 0.489362 (-460 3510);
PAINT MONO (-460 3510);
FORCEPROP 0 LASTPIN (-425 3450) $PN BH61
J 0
(-460 3460);
DISPLAY 0.489362 (-460 3460);
PAINT MONO (-460 3460);
FORCEPROP 0 LASTPIN (-425 3400) $PN BH64
J 0
(-460 3410);
DISPLAY 0.489362 (-460 3410);
PAINT MONO (-460 3410);
FORCEPROP 0 LASTPIN (-425 3350) $PN BH66
J 0
(-460 3360);
DISPLAY 0.489362 (-460 3360);
PAINT MONO (-460 3360);
FORCEPROP 0 LASTPIN (-425 3300) $PN BH68
J 0
(-460 3310);
DISPLAY 0.489362 (-460 3310);
PAINT MONO (-460 3310);
FORCEPROP 0 LASTPIN (-425 3250) $PN BH71
J 0
(-460 3260);
DISPLAY 0.489362 (-460 3260);
PAINT MONO (-460 3260);
FORCEPROP 0 LASTPIN (-425 3200) $PN BH73
J 0
(-460 3210);
DISPLAY 0.489362 (-460 3210);
PAINT MONO (-460 3210);
FORCEPROP 0 LASTPIN (-425 3150) $PN BJ1
J 0
(-460 3160);
DISPLAY 0.489362 (-460 3160);
PAINT MONO (-460 3160);
FORCEPROP 0 LASTPIN (-425 3100) $PN BJ6
J 0
(-460 3110);
DISPLAY 0.489362 (-460 3110);
PAINT MONO (-460 3110);
FORCEPROP 0 LASTPIN (-425 3050) $PN BJ8
J 0
(-460 3060);
DISPLAY 0.489362 (-460 3060);
PAINT MONO (-460 3060);
FORCEPROP 0 LASTPIN (-425 3000) $PN BJ13
J 0
(-460 3010);
DISPLAY 0.489362 (-460 3010);
PAINT MONO (-460 3010);
FORCEPROP 0 LASTPIN (-425 2950) $PN BJ15
J 0
(-460 2960);
DISPLAY 0.489362 (-460 2960);
PAINT MONO (-460 2960);
FORCEPROP 0 LASTPIN (-425 2900) $PN BJ20
J 0
(-460 2910);
DISPLAY 0.489362 (-460 2910);
PAINT MONO (-460 2910);
FORCEPROP 0 LASTPIN (-425 2850) $PN BJ22
J 0
(-460 2860);
DISPLAY 0.489362 (-460 2860);
PAINT MONO (-460 2860);
FORCEPROP 0 LASTPIN (-425 2800) $PN BJ24
J 0
(-460 2810);
DISPLAY 0.489362 (-460 2810);
PAINT MONO (-460 2810);
FORCEPROP 0 LASTPIN (-425 2750) $PN BJ26
J 0
(-460 2760);
DISPLAY 0.489362 (-460 2760);
PAINT MONO (-460 2760);
FORCEPROP 0 LASTPIN (-425 2700) $PN BJ28
J 0
(-460 2710);
DISPLAY 0.489362 (-460 2710);
PAINT MONO (-460 2710);
FORCEPROP 0 LASTPIN (-425 2650) $PN BJ49
J 0
(-460 2660);
DISPLAY 0.489362 (-460 2660);
PAINT MONO (-460 2660);
FORCEPROP 0 LASTPIN (-425 2600) $PN BJ51
J 0
(-460 2610);
DISPLAY 0.489362 (-460 2610);
PAINT MONO (-460 2610);
FORCEPROP 0 LASTPIN (-425 2550) $PN BJ53
J 0
(-460 2560);
DISPLAY 0.489362 (-460 2560);
PAINT MONO (-460 2560);
FORCEPROP 0 LASTPIN (-425 2500) $PN BJ56
J 0
(-460 2510);
DISPLAY 0.489362 (-460 2510);
PAINT MONO (-460 2510);
FORCEPROP 0 LASTPIN (-425 2450) $PN BJ61
J 0
(-460 2460);
DISPLAY 0.489362 (-460 2460);
PAINT MONO (-460 2460);
FORCEPROP 0 LASTPIN (-425 2400) $PN BJ63
J 0
(-460 2410);
DISPLAY 0.489362 (-460 2410);
PAINT MONO (-460 2410);
FORCEPROP 0 LASTPIN (-425 2350) $PN BJ68
J 0
(-460 2360);
DISPLAY 0.489362 (-460 2360);
PAINT MONO (-460 2360);
FORCEPROP 0 LASTPIN (-425 2300) $PN BJ70
J 0
(-460 2310);
DISPLAY 0.489362 (-460 2310);
PAINT MONO (-460 2310);
FORCEPROP 0 LASTPIN (-425 2250) $PN BJ75
J 0
(-460 2260);
DISPLAY 0.489362 (-460 2260);
PAINT MONO (-460 2260);
FORCEPROP 0 LASTPIN (-425 2200) $PN BK3
J 0
(-460 2210);
DISPLAY 0.489362 (-460 2210);
PAINT MONO (-460 2210);
FORCEPROP 0 LASTPIN (-425 2150) $PN BK5
J 0
(-460 2160);
DISPLAY 0.489362 (-460 2160);
PAINT MONO (-460 2160);
FORCEPROP 0 LASTPIN (-425 2100) $PN BK8
J 0
(-460 2110);
DISPLAY 0.489362 (-460 2110);
PAINT MONO (-460 2110);
FORCEPROP 0 LASTPIN (-425 2050) $PN BK10
J 0
(-460 2060);
DISPLAY 0.489362 (-460 2060);
PAINT MONO (-460 2060);
FORCEPROP 0 LASTPIN (-425 2000) $PN BK12
J 0
(-460 2010);
DISPLAY 0.489362 (-460 2010);
PAINT MONO (-460 2010);
FORCEPROP 0 LASTPIN (-425 1950) $PN BK15
J 0
(-460 1960);
DISPLAY 0.489362 (-460 1960);
PAINT MONO (-460 1960);
FORCEPROP 0 LASTPIN (-425 1900) $PN BK17
J 0
(-460 1910);
DISPLAY 0.489362 (-460 1910);
PAINT MONO (-460 1910);
FORCEPROP 0 LASTPIN (-425 1850) $PN BK19
J 0
(-460 1860);
DISPLAY 0.489362 (-460 1860);
PAINT MONO (-460 1860);
FORCEPROP 0 LASTPIN (-425 1800) $PN BK23
J 0
(-460 1810);
DISPLAY 0.489362 (-460 1810);
PAINT MONO (-460 1810);
FORCEPROP 0 LASTPIN (-425 1750) $PN BK25
J 0
(-460 1760);
DISPLAY 0.489362 (-460 1760);
PAINT MONO (-460 1760);
FORCEPROP 0 LASTPIN (-425 1700) $PN BK27
J 0
(-460 1710);
DISPLAY 0.489362 (-460 1710);
PAINT MONO (-460 1710);
FORCEPROP 0 LASTPIN (-425 1650) $PN BK48
J 0
(-460 1660);
DISPLAY 0.489362 (-460 1660);
PAINT MONO (-460 1660);
FORCEPROP 0 LASTPIN (-425 1600) $PN BK50
J 0
(-460 1610);
DISPLAY 0.489362 (-460 1610);
PAINT MONO (-460 1610);
FORCEPROP 0 LASTPIN (-425 1550) $PN BK52
J 0
(-460 1560);
DISPLAY 0.489362 (-460 1560);
PAINT MONO (-460 1560);
FORCEPROP 0 LASTPIN (-425 1500) $PN BK54
J 0
(-460 1510);
DISPLAY 0.489362 (-460 1510);
PAINT MONO (-460 1510);
FORCEPROP 0 LASTPIN (-425 1450) $PN BK57
J 0
(-460 1460);
DISPLAY 0.489362 (-460 1460);
PAINT MONO (-460 1460);
FORCEPROP 0 LASTPIN (-425 1400) $PN BK59
J 0
(-460 1410);
DISPLAY 0.489362 (-460 1410);
PAINT MONO (-460 1410);
FORCEPROP 0 LASTPIN (-425 1350) $PN BK61
J 0
(-460 1360);
DISPLAY 0.489362 (-460 1360);
PAINT MONO (-460 1360);
FORCEPROP 0 LASTPIN (-425 1300) $PN BK64
J 0
(-460 1310);
DISPLAY 0.489362 (-460 1310);
PAINT MONO (-460 1310);
FORCEPROP 0 LASTPIN (-425 1250) $PN BK66
J 0
(-460 1260);
DISPLAY 0.489362 (-460 1260);
PAINT MONO (-460 1260);
FORCEPROP 0 LASTPIN (-425 1200) $PN BK68
J 0
(-460 1210);
DISPLAY 0.489362 (-460 1210);
PAINT MONO (-460 1210);
FORCEPROP 0 LASTPIN (-425 1150) $PN BK71
J 0
(-460 1160);
DISPLAY 0.489362 (-460 1160);
PAINT MONO (-460 1160);
FORCEPROP 0 LASTPIN (-425 1100) $PN BK73
J 0
(-460 1110);
DISPLAY 0.489362 (-460 1110);
PAINT MONO (-460 1110);
FORCEPROP 0 LASTPIN (-425 1050) $PN BL1
J 0
(-460 1060);
DISPLAY 0.489362 (-460 1060);
PAINT MONO (-460 1060);
FORCEPROP 0 LASTPIN (-425 1000) $PN BL4
J 0
(-460 1010);
DISPLAY 0.489362 (-460 1010);
PAINT MONO (-460 1010);
FORCEPROP 0 LASTPIN (-425 950) $PN BL6
J 0
(-460 960);
DISPLAY 0.489362 (-460 960);
PAINT MONO (-460 960);
FORCEPROP 0 LASTPIN (-425 900) $PN BL8
J 0
(-460 910);
DISPLAY 0.489362 (-460 910);
PAINT MONO (-460 910);
FORCEPROP 0 LASTPIN (-425 850) $PN BL11
J 0
(-460 860);
DISPLAY 0.489362 (-460 860);
PAINT MONO (-460 860);
FORCEPROP 0 LASTPIN (-425 800) $PN BL13
J 0
(-460 810);
DISPLAY 0.489362 (-460 810);
PAINT MONO (-460 810);
FORCEPROP 0 LASTPIN (-425 750) $PN BL15
J 0
(-460 760);
DISPLAY 0.489362 (-460 760);
PAINT MONO (-460 760);
FORCEPROP 0 LASTPIN (-425 700) $PN BL18
J 0
(-460 710);
DISPLAY 0.489362 (-460 710);
PAINT MONO (-460 710);
FORCEPROP 0 LASTPIN (-425 650) $PN BL20
J 0
(-460 660);
DISPLAY 0.489362 (-460 660);
PAINT MONO (-460 660);
FORCEPROP 0 LASTPIN (-425 600) $PN BL22
J 0
(-460 610);
DISPLAY 0.489362 (-460 610);
PAINT MONO (-460 610);
FORCEPROP 0 LASTPIN (-425 550) $PN BL24
J 0
(-460 560);
DISPLAY 0.489362 (-460 560);
PAINT MONO (-460 560);
FORCEPROP 2 LAST PART_TYPE SMLF
J 0
(-1600 6675);
DISPLAY 1.021277 (-1600 6675);
FORCEPROP 1 LAST MATERIAL IO
J 0
(-1370 6582);
DISPLAY 0.489362 (-1370 6582);
PAINT SKYBLUE (-1370 6582);
FORCEPROP 2 LAST VALUE SOCKET6096_13568-001
J 0
(-1375 6625);
DISPLAY 0.489362 (-1375 6625);
PAINT SKYBLUE (-1375 6625);
FORCEPROP 1 LAST PART_NUMBER DGA^6000030
J 0
(-1375 6700);
DISPLAY 0.489362 (-1375 6700);
PAINT SKYBLUE (-1375 6700);
FORCEPROP 2 LAST CDS_LIB pure_quanta
J 0
(-975 3500);
DISPLAY INVISIBLE (-975 3500);
FORCEPROP 1 LAST CDS_LMAN_SYM_OUTLINE -400,3050,400,-3050
J 0
(-975 3500);
DISPLAY 0.468085 (-975 3500);
PAINT GREEN (-975 3500);
DISPLAY INVISIBLE (-975 3500);
FORCEPROP 1 LAST NEEDS_NO_SIZE TRUE
J 0
(-975 3500);
DISPLAY 0.723404 (-975 3500);
PAINT GREEN (-975 3500);
DISPLAY INVISIBLE (-975 3500);
FORCEPROP 1 LAST PATH I3
J 0
(-975 3500);
DISPLAY 0.723404 (-975 3500);
PAINT GREEN (-975 3500);
DISPLAY INVISIBLE (-975 3500);
FORCEADD GENOA_SP5..32
(-2600 3500);
FORCEPROP 1 LAST LOCATION U26
J 0
(-3000 6650);
DISPLAY 0.489362 (-3000 6650);
PAINT SKYBLUE (-3000 6650);
FORCEPROP 0 LAST $SEC 32
J 0
(-2975 6900);
DISPLAY 0.680851 (-2975 6900);
PAINT MONO (-2975 6900);
DISPLAY INVISIBLE (-2975 6900);
FORCEPROP 0 LAST CDS_SEC 32
J 0
(-2975 6900);
DISPLAY 1.021277 (-2975 6900);
DISPLAY INVISIBLE (-2975 6900);
FORCEPROP 0 LASTPIN (-3150 6400) $PN AM42
J 2
(-3160 6410);
DISPLAY 0.489362 (-3160 6410);
PAINT MONO (-3160 6410);
FORCEPROP 0 LASTPIN (-3150 6350) $PN AM43
J 2
(-3160 6360);
DISPLAY 0.489362 (-3160 6360);
PAINT MONO (-3160 6360);
FORCEPROP 0 LASTPIN (-3150 6300) $PN AM44
J 2
(-3160 6310);
DISPLAY 0.489362 (-3160 6310);
PAINT MONO (-3160 6310);
FORCEPROP 0 LASTPIN (-3150 6250) $PN AM45
J 2
(-3160 6260);
DISPLAY 0.489362 (-3160 6260);
PAINT MONO (-3160 6260);
FORCEPROP 0 LASTPIN (-3150 6200) $PN AM46
J 2
(-3160 6210);
DISPLAY 0.489362 (-3160 6210);
PAINT MONO (-3160 6210);
FORCEPROP 0 LASTPIN (-3150 6150) $PN AM47
J 2
(-3160 6160);
DISPLAY 0.489362 (-3160 6160);
PAINT MONO (-3160 6160);
FORCEPROP 0 LASTPIN (-3150 6100) $PN AM48
J 2
(-3160 6110);
DISPLAY 0.489362 (-3160 6110);
PAINT MONO (-3160 6110);
FORCEPROP 0 LASTPIN (-3150 6050) $PN AM49
J 2
(-3160 6060);
DISPLAY 0.489362 (-3160 6060);
PAINT MONO (-3160 6060);
FORCEPROP 0 LASTPIN (-3150 6000) $PN AM50
J 2
(-3160 6010);
DISPLAY 0.489362 (-3160 6010);
PAINT MONO (-3160 6010);
FORCEPROP 0 LASTPIN (-3150 5950) $PN AM51
J 2
(-3160 5960);
DISPLAY 0.489362 (-3160 5960);
PAINT MONO (-3160 5960);
FORCEPROP 0 LASTPIN (-3150 5900) $PN AM52
J 2
(-3160 5910);
DISPLAY 0.489362 (-3160 5910);
PAINT MONO (-3160 5910);
FORCEPROP 0 LASTPIN (-3150 5850) $PN AM53
J 2
(-3160 5860);
DISPLAY 0.489362 (-3160 5860);
PAINT MONO (-3160 5860);
FORCEPROP 0 LASTPIN (-3150 5800) $PN AM59
J 2
(-3160 5810);
DISPLAY 0.489362 (-3160 5810);
PAINT MONO (-3160 5810);
FORCEPROP 0 LASTPIN (-3150 5750) $PN AM61
J 2
(-3160 5760);
DISPLAY 0.489362 (-3160 5760);
PAINT MONO (-3160 5760);
FORCEPROP 0 LASTPIN (-3150 5700) $PN AM66
J 2
(-3160 5710);
DISPLAY 0.489362 (-3160 5710);
PAINT MONO (-3160 5710);
FORCEPROP 0 LASTPIN (-3150 5650) $PN AM68
J 2
(-3160 5660);
DISPLAY 0.489362 (-3160 5660);
PAINT MONO (-3160 5660);
FORCEPROP 0 LASTPIN (-3150 5600) $PN AM73
J 2
(-3160 5610);
DISPLAY 0.489362 (-3160 5610);
PAINT MONO (-3160 5610);
FORCEPROP 0 LASTPIN (-3150 5550) $PN AN1
J 2
(-3160 5560);
DISPLAY 0.489362 (-3160 5560);
PAINT MONO (-3160 5560);
FORCEPROP 0 LASTPIN (-3150 5500) $PN AN4
J 2
(-3160 5510);
DISPLAY 0.489362 (-3160 5510);
PAINT MONO (-3160 5510);
FORCEPROP 0 LASTPIN (-3150 5450) $PN AN6
J 2
(-3160 5460);
DISPLAY 0.489362 (-3160 5460);
PAINT MONO (-3160 5460);
FORCEPROP 0 LASTPIN (-3150 5400) $PN AN8
J 2
(-3160 5410);
DISPLAY 0.489362 (-3160 5410);
PAINT MONO (-3160 5410);
FORCEPROP 0 LASTPIN (-3150 5350) $PN AN11
J 2
(-3160 5360);
DISPLAY 0.489362 (-3160 5360);
PAINT MONO (-3160 5360);
FORCEPROP 0 LASTPIN (-3150 5300) $PN AN13
J 2
(-3160 5310);
DISPLAY 0.489362 (-3160 5310);
PAINT MONO (-3160 5310);
FORCEPROP 0 LASTPIN (-3150 5250) $PN AN15
J 2
(-3160 5260);
DISPLAY 0.489362 (-3160 5260);
PAINT MONO (-3160 5260);
FORCEPROP 0 LASTPIN (-3150 5200) $PN AN18
J 2
(-3160 5210);
DISPLAY 0.489362 (-3160 5210);
PAINT MONO (-3160 5210);
FORCEPROP 0 LASTPIN (-3150 5150) $PN AN22
J 2
(-3160 5160);
DISPLAY 0.489362 (-3160 5160);
PAINT MONO (-3160 5160);
FORCEPROP 0 LASTPIN (-3150 5100) $PN AN25
J 2
(-3160 5110);
DISPLAY 0.489362 (-3160 5110);
PAINT MONO (-3160 5110);
FORCEPROP 0 LASTPIN (-3150 5050) $PN AN28
J 2
(-3160 5060);
DISPLAY 0.489362 (-3160 5060);
PAINT MONO (-3160 5060);
FORCEPROP 0 LASTPIN (-3150 5000) $PN AN31
J 2
(-3160 5010);
DISPLAY 0.489362 (-3160 5010);
PAINT MONO (-3160 5010);
FORCEPROP 0 LASTPIN (-3150 4950) $PN AN34
J 2
(-3160 4960);
DISPLAY 0.489362 (-3160 4960);
PAINT MONO (-3160 4960);
FORCEPROP 0 LASTPIN (-3150 4900) $PN AN35
J 2
(-3160 4910);
DISPLAY 0.489362 (-3160 4910);
PAINT MONO (-3160 4910);
FORCEPROP 0 LASTPIN (-3150 4850) $PN AN36
J 2
(-3160 4860);
DISPLAY 0.489362 (-3160 4860);
PAINT MONO (-3160 4860);
FORCEPROP 0 LASTPIN (-3150 4800) $PN AN40
J 2
(-3160 4810);
DISPLAY 0.489362 (-3160 4810);
PAINT MONO (-3160 4810);
FORCEPROP 0 LASTPIN (-3150 4750) $PN AN41
J 2
(-3160 4760);
DISPLAY 0.489362 (-3160 4760);
PAINT MONO (-3160 4760);
FORCEPROP 0 LASTPIN (-3150 4700) $PN AN42
J 2
(-3160 4710);
DISPLAY 0.489362 (-3160 4710);
PAINT MONO (-3160 4710);
FORCEPROP 0 LASTPIN (-3150 4650) $PN AN45
J 2
(-3160 4660);
DISPLAY 0.489362 (-3160 4660);
PAINT MONO (-3160 4660);
FORCEPROP 0 LASTPIN (-3150 4600) $PN AN48
J 2
(-3160 4610);
DISPLAY 0.489362 (-3160 4610);
PAINT MONO (-3160 4610);
FORCEPROP 0 LASTPIN (-3150 4550) $PN AN51
J 2
(-3160 4560);
DISPLAY 0.489362 (-3160 4560);
PAINT MONO (-3160 4560);
FORCEPROP 0 LASTPIN (-3150 4500) $PN AN54
J 2
(-3160 4510);
DISPLAY 0.489362 (-3160 4510);
PAINT MONO (-3160 4510);
FORCEPROP 0 LASTPIN (-3150 4450) $PN AN56
J 2
(-3160 4460);
DISPLAY 0.489362 (-3160 4460);
PAINT MONO (-3160 4460);
FORCEPROP 0 LASTPIN (-3150 4400) $PN AN58
J 2
(-3160 4410);
DISPLAY 0.489362 (-3160 4410);
PAINT MONO (-3160 4410);
FORCEPROP 0 LASTPIN (-3150 4350) $PN AN61
J 2
(-3160 4360);
DISPLAY 0.489362 (-3160 4360);
PAINT MONO (-3160 4360);
FORCEPROP 0 LASTPIN (-3150 4300) $PN AN63
J 2
(-3160 4310);
DISPLAY 0.489362 (-3160 4310);
PAINT MONO (-3160 4310);
FORCEPROP 0 LASTPIN (-3150 4250) $PN AN65
J 2
(-3160 4260);
DISPLAY 0.489362 (-3160 4260);
PAINT MONO (-3160 4260);
FORCEPROP 0 LASTPIN (-3150 4200) $PN AN68
J 2
(-3160 4210);
DISPLAY 0.489362 (-3160 4210);
PAINT MONO (-3160 4210);
FORCEPROP 0 LASTPIN (-3150 4150) $PN AN70
J 2
(-3160 4160);
DISPLAY 0.489362 (-3160 4160);
PAINT MONO (-3160 4160);
FORCEPROP 0 LASTPIN (-3150 4100) $PN AN72
J 2
(-3160 4110);
DISPLAY 0.489362 (-3160 4110);
PAINT MONO (-3160 4110);
FORCEPROP 0 LASTPIN (-3150 4050) $PN AN75
J 2
(-3160 4060);
DISPLAY 0.489362 (-3160 4060);
PAINT MONO (-3160 4060);
FORCEPROP 0 LASTPIN (-3150 4000) $PN AP3
J 2
(-3160 4010);
DISPLAY 0.489362 (-3160 4010);
PAINT MONO (-3160 4010);
FORCEPROP 0 LASTPIN (-3150 3950) $PN AP5
J 2
(-3160 3960);
DISPLAY 0.489362 (-3160 3960);
PAINT MONO (-3160 3960);
FORCEPROP 0 LASTPIN (-3150 3900) $PN AP8
J 2
(-3160 3910);
DISPLAY 0.489362 (-3160 3910);
PAINT MONO (-3160 3910);
FORCEPROP 0 LASTPIN (-3150 3850) $PN AP10
J 2
(-3160 3860);
DISPLAY 0.489362 (-3160 3860);
PAINT MONO (-3160 3860);
FORCEPROP 0 LASTPIN (-3150 3800) $PN AP12
J 2
(-3160 3810);
DISPLAY 0.489362 (-3160 3810);
PAINT MONO (-3160 3810);
FORCEPROP 0 LASTPIN (-3150 3750) $PN AP15
J 2
(-3160 3760);
DISPLAY 0.489362 (-3160 3760);
PAINT MONO (-3160 3760);
FORCEPROP 0 LASTPIN (-3150 3700) $PN AP17
J 2
(-3160 3710);
DISPLAY 0.489362 (-3160 3710);
PAINT MONO (-3160 3710);
FORCEPROP 0 LASTPIN (-3150 3650) $PN AP19
J 2
(-3160 3660);
DISPLAY 0.489362 (-3160 3660);
PAINT MONO (-3160 3660);
FORCEPROP 0 LASTPIN (-3150 3600) $PN AP22
J 2
(-3160 3610);
DISPLAY 0.489362 (-3160 3610);
PAINT MONO (-3160 3610);
FORCEPROP 0 LASTPIN (-3150 3550) $PN AP25
J 2
(-3160 3560);
DISPLAY 0.489362 (-3160 3560);
PAINT MONO (-3160 3560);
FORCEPROP 0 LASTPIN (-3150 3500) $PN AP28
J 2
(-3160 3510);
DISPLAY 0.489362 (-3160 3510);
PAINT MONO (-3160 3510);
FORCEPROP 0 LASTPIN (-3150 3450) $PN AP31
J 2
(-3160 3460);
DISPLAY 0.489362 (-3160 3460);
PAINT MONO (-3160 3460);
FORCEPROP 0 LASTPIN (-3150 3400) $PN AP34
J 2
(-3160 3410);
DISPLAY 0.489362 (-3160 3410);
PAINT MONO (-3160 3410);
FORCEPROP 0 LASTPIN (-3150 3350) $PN AP37
J 2
(-3160 3360);
DISPLAY 0.489362 (-3160 3360);
PAINT MONO (-3160 3360);
FORCEPROP 0 LASTPIN (-3150 3300) $PN AP39
J 2
(-3160 3310);
DISPLAY 0.489362 (-3160 3310);
PAINT MONO (-3160 3310);
FORCEPROP 0 LASTPIN (-3150 3250) $PN AP42
J 2
(-3160 3260);
DISPLAY 0.489362 (-3160 3260);
PAINT MONO (-3160 3260);
FORCEPROP 0 LASTPIN (-3150 3200) $PN AP45
J 2
(-3160 3210);
DISPLAY 0.489362 (-3160 3210);
PAINT MONO (-3160 3210);
FORCEPROP 0 LASTPIN (-3150 3150) $PN AP48
J 2
(-3160 3160);
DISPLAY 0.489362 (-3160 3160);
PAINT MONO (-3160 3160);
FORCEPROP 0 LASTPIN (-3150 3100) $PN AP51
J 2
(-3160 3110);
DISPLAY 0.489362 (-3160 3110);
PAINT MONO (-3160 3110);
FORCEPROP 0 LASTPIN (-3150 3050) $PN AP54
J 2
(-3160 3060);
DISPLAY 0.489362 (-3160 3060);
PAINT MONO (-3160 3060);
FORCEPROP 0 LASTPIN (-3150 3000) $PN AP57
J 2
(-3160 3010);
DISPLAY 0.489362 (-3160 3010);
PAINT MONO (-3160 3010);
FORCEPROP 0 LASTPIN (-3150 2950) $PN AP59
J 2
(-3160 2960);
DISPLAY 0.489362 (-3160 2960);
PAINT MONO (-3160 2960);
FORCEPROP 0 LASTPIN (-3150 2900) $PN AP61
J 2
(-3160 2910);
DISPLAY 0.489362 (-3160 2910);
PAINT MONO (-3160 2910);
FORCEPROP 0 LASTPIN (-3150 2850) $PN AP64
J 2
(-3160 2860);
DISPLAY 0.489362 (-3160 2860);
PAINT MONO (-3160 2860);
FORCEPROP 0 LASTPIN (-3150 2800) $PN AP66
J 2
(-3160 2810);
DISPLAY 0.489362 (-3160 2810);
PAINT MONO (-3160 2810);
FORCEPROP 0 LASTPIN (-3150 2750) $PN AP68
J 2
(-3160 2760);
DISPLAY 0.489362 (-3160 2760);
PAINT MONO (-3160 2760);
FORCEPROP 0 LASTPIN (-3150 2700) $PN AP71
J 2
(-3160 2710);
DISPLAY 0.489362 (-3160 2710);
PAINT MONO (-3160 2710);
FORCEPROP 0 LASTPIN (-3150 2650) $PN AP73
J 2
(-3160 2660);
DISPLAY 0.489362 (-3160 2660);
PAINT MONO (-3160 2660);
FORCEPROP 0 LASTPIN (-3150 2600) $PN AR1
J 2
(-3160 2610);
DISPLAY 0.489362 (-3160 2610);
PAINT MONO (-3160 2610);
FORCEPROP 0 LASTPIN (-3150 2550) $PN AR5
J 2
(-3160 2560);
DISPLAY 0.489362 (-3160 2560);
PAINT MONO (-3160 2560);
FORCEPROP 0 LASTPIN (-3150 2500) $PN AR6
J 2
(-3160 2510);
DISPLAY 0.489362 (-3160 2510);
PAINT MONO (-3160 2510);
FORCEPROP 0 LASTPIN (-3150 2450) $PN AR8
J 2
(-3160 2460);
DISPLAY 0.489362 (-3160 2460);
PAINT MONO (-3160 2460);
FORCEPROP 0 LASTPIN (-3150 2400) $PN AR9
J 2
(-3160 2410);
DISPLAY 0.489362 (-3160 2410);
PAINT MONO (-3160 2410);
FORCEPROP 0 LASTPIN (-3150 2350) $PN AR12
J 2
(-3160 2360);
DISPLAY 0.489362 (-3160 2360);
PAINT MONO (-3160 2360);
FORCEPROP 0 LASTPIN (-3150 2300) $PN AR13
J 2
(-3160 2310);
DISPLAY 0.489362 (-3160 2310);
PAINT MONO (-3160 2310);
FORCEPROP 0 LASTPIN (-3150 2250) $PN AR15
J 2
(-3160 2260);
DISPLAY 0.489362 (-3160 2260);
PAINT MONO (-3160 2260);
FORCEPROP 0 LASTPIN (-3150 2200) $PN AR16
J 2
(-3160 2210);
DISPLAY 0.489362 (-3160 2210);
PAINT MONO (-3160 2210);
FORCEPROP 0 LASTPIN (-3150 2150) $PN AR19
J 2
(-3160 2160);
DISPLAY 0.489362 (-3160 2160);
PAINT MONO (-3160 2160);
FORCEPROP 0 LASTPIN (-3150 2100) $PN AR20
J 2
(-3160 2110);
DISPLAY 0.489362 (-3160 2110);
PAINT MONO (-3160 2110);
FORCEPROP 0 LASTPIN (-3150 2050) $PN AR22
J 2
(-3160 2060);
DISPLAY 0.489362 (-3160 2060);
PAINT MONO (-3160 2060);
FORCEPROP 0 LASTPIN (-3150 2000) $PN AR24
J 2
(-3160 2010);
DISPLAY 0.489362 (-3160 2010);
PAINT MONO (-3160 2010);
FORCEPROP 0 LASTPIN (-3150 1950) $PN AR26
J 2
(-3160 1960);
DISPLAY 0.489362 (-3160 1960);
PAINT MONO (-3160 1960);
FORCEPROP 0 LASTPIN (-3150 1900) $PN AR28
J 2
(-3160 1910);
DISPLAY 0.489362 (-3160 1910);
PAINT MONO (-3160 1910);
FORCEPROP 0 LASTPIN (-3150 1850) $PN AR30
J 2
(-3160 1860);
DISPLAY 0.489362 (-3160 1860);
PAINT MONO (-3160 1860);
FORCEPROP 0 LASTPIN (-3150 1800) $PN AR32
J 2
(-3160 1810);
DISPLAY 0.489362 (-3160 1810);
PAINT MONO (-3160 1810);
FORCEPROP 0 LASTPIN (-3150 1750) $PN AR34
J 2
(-3160 1760);
DISPLAY 0.489362 (-3160 1760);
PAINT MONO (-3160 1760);
FORCEPROP 0 LASTPIN (-3150 1700) $PN AR36
J 2
(-3160 1710);
DISPLAY 0.489362 (-3160 1710);
PAINT MONO (-3160 1710);
FORCEPROP 0 LASTPIN (-3150 1650) $PN AR41
J 2
(-3160 1660);
DISPLAY 0.489362 (-3160 1660);
PAINT MONO (-3160 1660);
FORCEPROP 0 LASTPIN (-3150 1600) $PN AR43
J 2
(-3160 1610);
DISPLAY 0.489362 (-3160 1610);
PAINT MONO (-3160 1610);
FORCEPROP 0 LASTPIN (-3150 1550) $PN AR45
J 2
(-3160 1560);
DISPLAY 0.489362 (-3160 1560);
PAINT MONO (-3160 1560);
FORCEPROP 0 LASTPIN (-3150 1500) $PN AR47
J 2
(-3160 1510);
DISPLAY 0.489362 (-3160 1510);
PAINT MONO (-3160 1510);
FORCEPROP 0 LASTPIN (-3150 1450) $PN AR49
J 2
(-3160 1460);
DISPLAY 0.489362 (-3160 1460);
PAINT MONO (-3160 1460);
FORCEPROP 0 LASTPIN (-3150 1400) $PN AR51
J 2
(-3160 1410);
DISPLAY 0.489362 (-3160 1410);
PAINT MONO (-3160 1410);
FORCEPROP 0 LASTPIN (-3150 1350) $PN AR53
J 2
(-3160 1360);
DISPLAY 0.489362 (-3160 1360);
PAINT MONO (-3160 1360);
FORCEPROP 0 LASTPIN (-3150 1300) $PN AR56
J 2
(-3160 1310);
DISPLAY 0.489362 (-3160 1310);
PAINT MONO (-3160 1310);
FORCEPROP 0 LASTPIN (-3150 1250) $PN AR57
J 2
(-3160 1260);
DISPLAY 0.489362 (-3160 1260);
PAINT MONO (-3160 1260);
FORCEPROP 0 LASTPIN (-3150 1200) $PN AR60
J 2
(-3160 1210);
DISPLAY 0.489362 (-3160 1210);
PAINT MONO (-3160 1210);
FORCEPROP 0 LASTPIN (-3150 1150) $PN AR61
J 2
(-3160 1160);
DISPLAY 0.489362 (-3160 1160);
PAINT MONO (-3160 1160);
FORCEPROP 0 LASTPIN (-3150 1100) $PN AR63
J 2
(-3160 1110);
DISPLAY 0.489362 (-3160 1110);
PAINT MONO (-3160 1110);
FORCEPROP 0 LASTPIN (-3150 1050) $PN AR64
J 2
(-3160 1060);
DISPLAY 0.489362 (-3160 1060);
PAINT MONO (-3160 1060);
FORCEPROP 0 LASTPIN (-3150 1000) $PN AR67
J 2
(-3160 1010);
DISPLAY 0.489362 (-3160 1010);
PAINT MONO (-3160 1010);
FORCEPROP 0 LASTPIN (-3150 950) $PN AR68
J 2
(-3160 960);
DISPLAY 0.489362 (-3160 960);
PAINT MONO (-3160 960);
FORCEPROP 0 LASTPIN (-3150 900) $PN AR70
J 2
(-3160 910);
DISPLAY 0.489362 (-3160 910);
PAINT MONO (-3160 910);
FORCEPROP 0 LASTPIN (-3150 850) $PN AR71
J 2
(-3160 860);
DISPLAY 0.489362 (-3160 860);
PAINT MONO (-3160 860);
FORCEPROP 0 LASTPIN (-3150 800) $PN AR75
J 2
(-3160 810);
DISPLAY 0.489362 (-3160 810);
PAINT MONO (-3160 810);
FORCEPROP 0 LASTPIN (-3150 750) $PN AT3
J 2
(-3160 760);
DISPLAY 0.489362 (-3160 760);
PAINT MONO (-3160 760);
FORCEPROP 0 LASTPIN (-3150 700) $PN AT4
J 2
(-3160 710);
DISPLAY 0.489362 (-3160 710);
PAINT MONO (-3160 710);
FORCEPROP 0 LASTPIN (-3150 650) $PN AT5
J 2
(-3160 660);
DISPLAY 0.489362 (-3160 660);
PAINT MONO (-3160 660);
FORCEPROP 0 LASTPIN (-3150 600) $PN AT6
J 2
(-3160 610);
DISPLAY 0.489362 (-3160 610);
PAINT MONO (-3160 610);
FORCEPROP 0 LASTPIN (-3150 550) $PN AT8
J 2
(-3160 560);
DISPLAY 0.489362 (-3160 560);
PAINT MONO (-3160 560);
FORCEPROP 0 LASTPIN (-2050 6450) $PN AT9
J 0
(-2085 6460);
DISPLAY 0.489362 (-2085 6460);
PAINT MONO (-2085 6460);
FORCEPROP 0 LASTPIN (-2050 6400) $PN AT10
J 0
(-2085 6410);
DISPLAY 0.489362 (-2085 6410);
PAINT MONO (-2085 6410);
FORCEPROP 0 LASTPIN (-2050 6350) $PN AT12
J 0
(-2085 6360);
DISPLAY 0.489362 (-2085 6360);
PAINT MONO (-2085 6360);
FORCEPROP 0 LASTPIN (-2050 6300) $PN AT13
J 0
(-2085 6310);
DISPLAY 0.489362 (-2085 6310);
PAINT MONO (-2085 6310);
FORCEPROP 0 LASTPIN (-2050 6250) $PN AT15
J 0
(-2085 6260);
DISPLAY 0.489362 (-2085 6260);
PAINT MONO (-2085 6260);
FORCEPROP 0 LASTPIN (-2050 6200) $PN AT16
J 0
(-2085 6210);
DISPLAY 0.489362 (-2085 6210);
PAINT MONO (-2085 6210);
FORCEPROP 0 LASTPIN (-2050 6150) $PN AT17
J 0
(-2085 6160);
DISPLAY 0.489362 (-2085 6160);
PAINT MONO (-2085 6160);
FORCEPROP 0 LASTPIN (-2050 6100) $PN AT19
J 0
(-2085 6110);
DISPLAY 0.489362 (-2085 6110);
PAINT MONO (-2085 6110);
FORCEPROP 0 LASTPIN (-2050 6050) $PN AT20
J 0
(-2085 6060);
DISPLAY 0.489362 (-2085 6060);
PAINT MONO (-2085 6060);
FORCEPROP 0 LASTPIN (-2050 6000) $PN AT23
J 0
(-2085 6010);
DISPLAY 0.489362 (-2085 6010);
PAINT MONO (-2085 6010);
FORCEPROP 0 LASTPIN (-2050 5950) $PN AT25
J 0
(-2085 5960);
DISPLAY 0.489362 (-2085 5960);
PAINT MONO (-2085 5960);
FORCEPROP 0 LASTPIN (-2050 5900) $PN AT27
J 0
(-2085 5910);
DISPLAY 0.489362 (-2085 5910);
PAINT MONO (-2085 5910);
FORCEPROP 0 LASTPIN (-2050 5850) $PN AT29
J 0
(-2085 5860);
DISPLAY 0.489362 (-2085 5860);
PAINT MONO (-2085 5860);
FORCEPROP 0 LASTPIN (-2050 5800) $PN AT31
J 0
(-2085 5810);
DISPLAY 0.489362 (-2085 5810);
PAINT MONO (-2085 5810);
FORCEPROP 0 LASTPIN (-2050 5750) $PN AT33
J 0
(-2085 5760);
DISPLAY 0.489362 (-2085 5760);
PAINT MONO (-2085 5760);
FORCEPROP 0 LASTPIN (-2050 5700) $PN AT35
J 0
(-2085 5710);
DISPLAY 0.489362 (-2085 5710);
PAINT MONO (-2085 5710);
FORCEPROP 0 LASTPIN (-2050 5650) $PN AT37
J 0
(-2085 5660);
DISPLAY 0.489362 (-2085 5660);
PAINT MONO (-2085 5660);
FORCEPROP 0 LASTPIN (-2050 5600) $PN AT40
J 0
(-2085 5610);
DISPLAY 0.489362 (-2085 5610);
PAINT MONO (-2085 5610);
FORCEPROP 0 LASTPIN (-2050 5550) $PN AT42
J 0
(-2085 5560);
DISPLAY 0.489362 (-2085 5560);
PAINT MONO (-2085 5560);
FORCEPROP 0 LASTPIN (-2050 5500) $PN AT44
J 0
(-2085 5510);
DISPLAY 0.489362 (-2085 5510);
PAINT MONO (-2085 5510);
FORCEPROP 0 LASTPIN (-2050 5450) $PN AT46
J 0
(-2085 5460);
DISPLAY 0.489362 (-2085 5460);
PAINT MONO (-2085 5460);
FORCEPROP 0 LASTPIN (-2050 5400) $PN AT48
J 0
(-2085 5410);
DISPLAY 0.489362 (-2085 5410);
PAINT MONO (-2085 5410);
FORCEPROP 0 LASTPIN (-2050 5350) $PN AT50
J 0
(-2085 5360);
DISPLAY 0.489362 (-2085 5360);
PAINT MONO (-2085 5360);
FORCEPROP 0 LASTPIN (-2050 5300) $PN AT52
J 0
(-2085 5310);
DISPLAY 0.489362 (-2085 5310);
PAINT MONO (-2085 5310);
FORCEPROP 0 LASTPIN (-2050 5250) $PN AT54
J 0
(-2085 5260);
DISPLAY 0.489362 (-2085 5260);
PAINT MONO (-2085 5260);
FORCEPROP 0 LASTPIN (-2050 5200) $PN AT56
J 0
(-2085 5210);
DISPLAY 0.489362 (-2085 5210);
PAINT MONO (-2085 5210);
FORCEPROP 0 LASTPIN (-2050 5150) $PN AT57
J 0
(-2085 5160);
DISPLAY 0.489362 (-2085 5160);
PAINT MONO (-2085 5160);
FORCEPROP 0 LASTPIN (-2050 5100) $PN AT59
J 0
(-2085 5110);
DISPLAY 0.489362 (-2085 5110);
PAINT MONO (-2085 5110);
FORCEPROP 0 LASTPIN (-2050 5050) $PN AT60
J 0
(-2085 5060);
DISPLAY 0.489362 (-2085 5060);
PAINT MONO (-2085 5060);
FORCEPROP 0 LASTPIN (-2050 5000) $PN AT61
J 0
(-2085 5010);
DISPLAY 0.489362 (-2085 5010);
PAINT MONO (-2085 5010);
FORCEPROP 0 LASTPIN (-2050 4950) $PN AT63
J 0
(-2085 4960);
DISPLAY 0.489362 (-2085 4960);
PAINT MONO (-2085 4960);
FORCEPROP 0 LASTPIN (-2050 4900) $PN AT64
J 0
(-2085 4910);
DISPLAY 0.489362 (-2085 4910);
PAINT MONO (-2085 4910);
FORCEPROP 0 LASTPIN (-2050 4850) $PN AT66
J 0
(-2085 4860);
DISPLAY 0.489362 (-2085 4860);
PAINT MONO (-2085 4860);
FORCEPROP 0 LASTPIN (-2050 4800) $PN AT67
J 0
(-2085 4810);
DISPLAY 0.489362 (-2085 4810);
PAINT MONO (-2085 4810);
FORCEPROP 0 LASTPIN (-2050 4750) $PN AT68
J 0
(-2085 4760);
DISPLAY 0.489362 (-2085 4760);
PAINT MONO (-2085 4760);
FORCEPROP 0 LASTPIN (-2050 4700) $PN AT70
J 0
(-2085 4710);
DISPLAY 0.489362 (-2085 4710);
PAINT MONO (-2085 4710);
FORCEPROP 0 LASTPIN (-2050 4650) $PN AT71
J 0
(-2085 4660);
DISPLAY 0.489362 (-2085 4660);
PAINT MONO (-2085 4660);
FORCEPROP 0 LASTPIN (-2050 4600) $PN AT72
J 0
(-2085 4610);
DISPLAY 0.489362 (-2085 4610);
PAINT MONO (-2085 4610);
FORCEPROP 0 LASTPIN (-2050 4550) $PN AT73
J 0
(-2085 4560);
DISPLAY 0.489362 (-2085 4560);
PAINT MONO (-2085 4560);
FORCEPROP 0 LASTPIN (-2050 4500) $PN AU1
J 0
(-2085 4510);
DISPLAY 0.489362 (-2085 4510);
PAINT MONO (-2085 4510);
FORCEPROP 0 LASTPIN (-2050 4450) $PN AU3
J 0
(-2085 4460);
DISPLAY 0.489362 (-2085 4460);
PAINT MONO (-2085 4460);
FORCEPROP 0 LASTPIN (-2050 4400) $PN AU4
J 0
(-2085 4410);
DISPLAY 0.489362 (-2085 4410);
PAINT MONO (-2085 4410);
FORCEPROP 0 LASTPIN (-2050 4350) $PN AU6
J 0
(-2085 4360);
DISPLAY 0.489362 (-2085 4360);
PAINT MONO (-2085 4360);
FORCEPROP 0 LASTPIN (-2050 4300) $PN AU8
J 0
(-2085 4310);
DISPLAY 0.489362 (-2085 4310);
PAINT MONO (-2085 4310);
FORCEPROP 0 LASTPIN (-2050 4250) $PN AU11
J 0
(-2085 4260);
DISPLAY 0.489362 (-2085 4260);
PAINT MONO (-2085 4260);
FORCEPROP 0 LASTPIN (-2050 4200) $PN AU13
J 0
(-2085 4210);
DISPLAY 0.489362 (-2085 4210);
PAINT MONO (-2085 4210);
FORCEPROP 0 LASTPIN (-2050 4150) $PN AU15
J 0
(-2085 4160);
DISPLAY 0.489362 (-2085 4160);
PAINT MONO (-2085 4160);
FORCEPROP 0 LASTPIN (-2050 4100) $PN AU18
J 0
(-2085 4110);
DISPLAY 0.489362 (-2085 4110);
PAINT MONO (-2085 4110);
FORCEPROP 0 LASTPIN (-2050 4050) $PN AU20
J 0
(-2085 4060);
DISPLAY 0.489362 (-2085 4060);
PAINT MONO (-2085 4060);
FORCEPROP 0 LASTPIN (-2050 4000) $PN AU22
J 0
(-2085 4010);
DISPLAY 0.489362 (-2085 4010);
PAINT MONO (-2085 4010);
FORCEPROP 0 LASTPIN (-2050 3950) $PN AU24
J 0
(-2085 3960);
DISPLAY 0.489362 (-2085 3960);
PAINT MONO (-2085 3960);
FORCEPROP 0 LASTPIN (-2050 3900) $PN AU26
J 0
(-2085 3910);
DISPLAY 0.489362 (-2085 3910);
PAINT MONO (-2085 3910);
FORCEPROP 0 LASTPIN (-2050 3850) $PN AU28
J 0
(-2085 3860);
DISPLAY 0.489362 (-2085 3860);
PAINT MONO (-2085 3860);
FORCEPROP 0 LASTPIN (-2050 3800) $PN AU30
J 0
(-2085 3810);
DISPLAY 0.489362 (-2085 3810);
PAINT MONO (-2085 3810);
FORCEPROP 0 LASTPIN (-2050 3750) $PN AU32
J 0
(-2085 3760);
DISPLAY 0.489362 (-2085 3760);
PAINT MONO (-2085 3760);
FORCEPROP 0 LASTPIN (-2050 3700) $PN AU34
J 0
(-2085 3710);
DISPLAY 0.489362 (-2085 3710);
PAINT MONO (-2085 3710);
FORCEPROP 0 LASTPIN (-2050 3650) $PN AU36
J 0
(-2085 3660);
DISPLAY 0.489362 (-2085 3660);
PAINT MONO (-2085 3660);
FORCEPROP 0 LASTPIN (-2050 3600) $PN AU41
J 0
(-2085 3610);
DISPLAY 0.489362 (-2085 3610);
PAINT MONO (-2085 3610);
FORCEPROP 0 LASTPIN (-2050 3550) $PN AU43
J 0
(-2085 3560);
DISPLAY 0.489362 (-2085 3560);
PAINT MONO (-2085 3560);
FORCEPROP 0 LASTPIN (-2050 3500) $PN AU45
J 0
(-2085 3510);
DISPLAY 0.489362 (-2085 3510);
PAINT MONO (-2085 3510);
FORCEPROP 0 LASTPIN (-2050 3450) $PN AU47
J 0
(-2085 3460);
DISPLAY 0.489362 (-2085 3460);
PAINT MONO (-2085 3460);
FORCEPROP 0 LASTPIN (-2050 3400) $PN AU49
J 0
(-2085 3410);
DISPLAY 0.489362 (-2085 3410);
PAINT MONO (-2085 3410);
FORCEPROP 0 LASTPIN (-2050 3350) $PN AU51
J 0
(-2085 3360);
DISPLAY 0.489362 (-2085 3360);
PAINT MONO (-2085 3360);
FORCEPROP 0 LASTPIN (-2050 3300) $PN AU53
J 0
(-2085 3310);
DISPLAY 0.489362 (-2085 3310);
PAINT MONO (-2085 3310);
FORCEPROP 0 LASTPIN (-2050 3250) $PN AU56
J 0
(-2085 3260);
DISPLAY 0.489362 (-2085 3260);
PAINT MONO (-2085 3260);
FORCEPROP 0 LASTPIN (-2050 3200) $PN AU58
J 0
(-2085 3210);
DISPLAY 0.489362 (-2085 3210);
PAINT MONO (-2085 3210);
FORCEPROP 0 LASTPIN (-2050 3150) $PN AU61
J 0
(-2085 3160);
DISPLAY 0.489362 (-2085 3160);
PAINT MONO (-2085 3160);
FORCEPROP 0 LASTPIN (-2050 3100) $PN AU63
J 0
(-2085 3110);
DISPLAY 0.489362 (-2085 3110);
PAINT MONO (-2085 3110);
FORCEPROP 0 LASTPIN (-2050 3050) $PN AU65
J 0
(-2085 3060);
DISPLAY 0.489362 (-2085 3060);
PAINT MONO (-2085 3060);
FORCEPROP 0 LASTPIN (-2050 3000) $PN AU68
J 0
(-2085 3010);
DISPLAY 0.489362 (-2085 3010);
PAINT MONO (-2085 3010);
FORCEPROP 0 LASTPIN (-2050 2950) $PN AU70
J 0
(-2085 2960);
DISPLAY 0.489362 (-2085 2960);
PAINT MONO (-2085 2960);
FORCEPROP 0 LASTPIN (-2050 2900) $PN AU72
J 0
(-2085 2910);
DISPLAY 0.489362 (-2085 2910);
PAINT MONO (-2085 2910);
FORCEPROP 0 LASTPIN (-2050 2850) $PN AU73
J 0
(-2085 2860);
DISPLAY 0.489362 (-2085 2860);
PAINT MONO (-2085 2860);
FORCEPROP 0 LASTPIN (-2050 2800) $PN AU75
J 0
(-2085 2810);
DISPLAY 0.489362 (-2085 2810);
PAINT MONO (-2085 2810);
FORCEPROP 0 LASTPIN (-2050 2750) $PN AV3
J 0
(-2085 2760);
DISPLAY 0.489362 (-2085 2760);
PAINT MONO (-2085 2760);
FORCEPROP 0 LASTPIN (-2050 2700) $PN AV8
J 0
(-2085 2710);
DISPLAY 0.489362 (-2085 2710);
PAINT MONO (-2085 2710);
FORCEPROP 0 LASTPIN (-2050 2650) $PN AV10
J 0
(-2085 2660);
DISPLAY 0.489362 (-2085 2660);
PAINT MONO (-2085 2660);
FORCEPROP 0 LASTPIN (-2050 2600) $PN AV15
J 0
(-2085 2610);
DISPLAY 0.489362 (-2085 2610);
PAINT MONO (-2085 2610);
FORCEPROP 0 LASTPIN (-2050 2550) $PN AV17
J 0
(-2085 2560);
DISPLAY 0.489362 (-2085 2560);
PAINT MONO (-2085 2560);
FORCEPROP 0 LASTPIN (-2050 2500) $PN AV23
J 0
(-2085 2510);
DISPLAY 0.489362 (-2085 2510);
PAINT MONO (-2085 2510);
FORCEPROP 0 LASTPIN (-2050 2450) $PN AV25
J 0
(-2085 2460);
DISPLAY 0.489362 (-2085 2460);
PAINT MONO (-2085 2460);
FORCEPROP 0 LASTPIN (-2050 2400) $PN AV27
J 0
(-2085 2410);
DISPLAY 0.489362 (-2085 2410);
PAINT MONO (-2085 2410);
FORCEPROP 0 LASTPIN (-2050 2350) $PN AV29
J 0
(-2085 2360);
DISPLAY 0.489362 (-2085 2360);
PAINT MONO (-2085 2360);
FORCEPROP 0 LASTPIN (-2050 2300) $PN AV31
J 0
(-2085 2310);
DISPLAY 0.489362 (-2085 2310);
PAINT MONO (-2085 2310);
FORCEPROP 0 LASTPIN (-2050 2250) $PN AV33
J 0
(-2085 2260);
DISPLAY 0.489362 (-2085 2260);
PAINT MONO (-2085 2260);
FORCEPROP 0 LASTPIN (-2050 2200) $PN AV35
J 0
(-2085 2210);
DISPLAY 0.489362 (-2085 2210);
PAINT MONO (-2085 2210);
FORCEPROP 0 LASTPIN (-2050 2150) $PN AV37
J 0
(-2085 2160);
DISPLAY 0.489362 (-2085 2160);
PAINT MONO (-2085 2160);
FORCEPROP 0 LASTPIN (-2050 2100) $PN AV40
J 0
(-2085 2110);
DISPLAY 0.489362 (-2085 2110);
PAINT MONO (-2085 2110);
FORCEPROP 0 LASTPIN (-2050 2050) $PN AV42
J 0
(-2085 2060);
DISPLAY 0.489362 (-2085 2060);
PAINT MONO (-2085 2060);
FORCEPROP 0 LASTPIN (-2050 2000) $PN AV44
J 0
(-2085 2010);
DISPLAY 0.489362 (-2085 2010);
PAINT MONO (-2085 2010);
FORCEPROP 0 LASTPIN (-2050 1950) $PN AV46
J 0
(-2085 1960);
DISPLAY 0.489362 (-2085 1960);
PAINT MONO (-2085 1960);
FORCEPROP 0 LASTPIN (-2050 1900) $PN AV48
J 0
(-2085 1910);
DISPLAY 0.489362 (-2085 1910);
PAINT MONO (-2085 1910);
FORCEPROP 0 LASTPIN (-2050 1850) $PN AV50
J 0
(-2085 1860);
DISPLAY 0.489362 (-2085 1860);
PAINT MONO (-2085 1860);
FORCEPROP 0 LASTPIN (-2050 1800) $PN AV52
J 0
(-2085 1810);
DISPLAY 0.489362 (-2085 1810);
PAINT MONO (-2085 1810);
FORCEPROP 0 LASTPIN (-2050 1750) $PN AV54
J 0
(-2085 1760);
DISPLAY 0.489362 (-2085 1760);
PAINT MONO (-2085 1760);
FORCEPROP 0 LASTPIN (-2050 1700) $PN AV59
J 0
(-2085 1710);
DISPLAY 0.489362 (-2085 1710);
PAINT MONO (-2085 1710);
FORCEPROP 0 LASTPIN (-2050 1650) $PN AV61
J 0
(-2085 1660);
DISPLAY 0.489362 (-2085 1660);
PAINT MONO (-2085 1660);
FORCEPROP 0 LASTPIN (-2050 1600) $PN AV66
J 0
(-2085 1610);
DISPLAY 0.489362 (-2085 1610);
PAINT MONO (-2085 1610);
FORCEPROP 0 LASTPIN (-2050 1550) $PN AV68
J 0
(-2085 1560);
DISPLAY 0.489362 (-2085 1560);
PAINT MONO (-2085 1560);
FORCEPROP 0 LASTPIN (-2050 1500) $PN AV73
J 0
(-2085 1510);
DISPLAY 0.489362 (-2085 1510);
PAINT MONO (-2085 1510);
FORCEPROP 0 LASTPIN (-2050 1450) $PN AW1
J 0
(-2085 1460);
DISPLAY 0.489362 (-2085 1460);
PAINT MONO (-2085 1460);
FORCEPROP 0 LASTPIN (-2050 1400) $PN AW4
J 0
(-2085 1410);
DISPLAY 0.489362 (-2085 1410);
PAINT MONO (-2085 1410);
FORCEPROP 0 LASTPIN (-2050 1350) $PN AW6
J 0
(-2085 1360);
DISPLAY 0.489362 (-2085 1360);
PAINT MONO (-2085 1360);
FORCEPROP 0 LASTPIN (-2050 1300) $PN AW8
J 0
(-2085 1310);
DISPLAY 0.489362 (-2085 1310);
PAINT MONO (-2085 1310);
FORCEPROP 0 LASTPIN (-2050 1250) $PN AW11
J 0
(-2085 1260);
DISPLAY 0.489362 (-2085 1260);
PAINT MONO (-2085 1260);
FORCEPROP 0 LASTPIN (-2050 1200) $PN AW13
J 0
(-2085 1210);
DISPLAY 0.489362 (-2085 1210);
PAINT MONO (-2085 1210);
FORCEPROP 0 LASTPIN (-2050 1150) $PN AW15
J 0
(-2085 1160);
DISPLAY 0.489362 (-2085 1160);
PAINT MONO (-2085 1160);
FORCEPROP 0 LASTPIN (-2050 1100) $PN AW18
J 0
(-2085 1110);
DISPLAY 0.489362 (-2085 1110);
PAINT MONO (-2085 1110);
FORCEPROP 0 LASTPIN (-2050 1050) $PN AW20
J 0
(-2085 1060);
DISPLAY 0.489362 (-2085 1060);
PAINT MONO (-2085 1060);
FORCEPROP 0 LASTPIN (-2050 1000) $PN AW22
J 0
(-2085 1010);
DISPLAY 0.489362 (-2085 1010);
PAINT MONO (-2085 1010);
FORCEPROP 0 LASTPIN (-2050 950) $PN AW24
J 0
(-2085 960);
DISPLAY 0.489362 (-2085 960);
PAINT MONO (-2085 960);
FORCEPROP 0 LASTPIN (-2050 900) $PN AW26
J 0
(-2085 910);
DISPLAY 0.489362 (-2085 910);
PAINT MONO (-2085 910);
FORCEPROP 0 LASTPIN (-2050 850) $PN AW28
J 0
(-2085 860);
DISPLAY 0.489362 (-2085 860);
PAINT MONO (-2085 860);
FORCEPROP 0 LASTPIN (-2050 800) $PN AW49
J 0
(-2085 810);
DISPLAY 0.489362 (-2085 810);
PAINT MONO (-2085 810);
FORCEPROP 0 LASTPIN (-2050 750) $PN AW51
J 0
(-2085 760);
DISPLAY 0.489362 (-2085 760);
PAINT MONO (-2085 760);
FORCEPROP 0 LASTPIN (-2050 700) $PN AW53
J 0
(-2085 710);
DISPLAY 0.489362 (-2085 710);
PAINT MONO (-2085 710);
FORCEPROP 0 LASTPIN (-2050 650) $PN AW56
J 0
(-2085 660);
DISPLAY 0.489362 (-2085 660);
PAINT MONO (-2085 660);
FORCEPROP 0 LASTPIN (-2050 600) $PN AW58
J 0
(-2085 610);
DISPLAY 0.489362 (-2085 610);
PAINT MONO (-2085 610);
FORCEPROP 0 LASTPIN (-2050 550) $PN AW61
J 0
(-2085 560);
DISPLAY 0.489362 (-2085 560);
PAINT MONO (-2085 560);
FORCEPROP 2 LAST PART_TYPE SMLF
J 0
(-3200 6700);
DISPLAY 1.021277 (-3200 6700);
FORCEPROP 1 LAST MATERIAL IO
J 0
(-2995 6582);
DISPLAY 0.489362 (-2995 6582);
PAINT SKYBLUE (-2995 6582);
FORCEPROP 2 LAST VALUE SOCKET6096_13568-001
J 0
(-3000 6625);
DISPLAY 0.489362 (-3000 6625);
PAINT SKYBLUE (-3000 6625);
FORCEPROP 1 LAST PART_NUMBER DGA^6000030
J 0
(-2995 6709);
DISPLAY 0.489362 (-2995 6709);
PAINT SKYBLUE (-2995 6709);
FORCEPROP 2 LAST CDS_LIB pure_quanta
J 0
(-2600 3500);
DISPLAY INVISIBLE (-2600 3500);
FORCEPROP 1 LAST CDS_LMAN_SYM_OUTLINE -400,3050,400,-3050
J 0
(-2600 3500);
DISPLAY 0.468085 (-2600 3500);
PAINT GREEN (-2600 3500);
DISPLAY INVISIBLE (-2600 3500);
FORCEPROP 1 LAST NEEDS_NO_SIZE TRUE
J 0
(-2600 3500);
DISPLAY 0.723404 (-2600 3500);
PAINT GREEN (-2600 3500);
DISPLAY INVISIBLE (-2600 3500);
FORCEPROP 1 LAST PATH I6
J 0
(-2600 3500);
DISPLAY 0.723404 (-2600 3500);
PAINT GREEN (-2600 3500);
DISPLAY INVISIBLE (-2600 3500);
FORCEADD GENOA_SP5..31
(-4075 3500);
FORCEPROP 1 LAST LOCATION U26
J 0
(-4475 6650);
DISPLAY 0.489362 (-4475 6650);
PAINT SKYBLUE (-4475 6650);
FORCEPROP 0 LAST $SEC 31
J 0
(-4450 6900);
DISPLAY 0.680851 (-4450 6900);
PAINT MONO (-4450 6900);
DISPLAY INVISIBLE (-4450 6900);
FORCEPROP 0 LAST CDS_SEC 31
J 0
(-4450 6900);
DISPLAY 1.021277 (-4450 6900);
DISPLAY INVISIBLE (-4450 6900);
FORCEPROP 0 LASTPIN (-4625 6400) $PN AD49
J 2
(-4585 6410);
DISPLAY 0.489362 (-4585 6410);
PAINT MONO (-4585 6410);
FORCEPROP 0 LASTPIN (-4625 6350) $PN AD50
J 2
(-4585 6360);
DISPLAY 0.489362 (-4585 6360);
PAINT MONO (-4585 6360);
FORCEPROP 0 LASTPIN (-4625 6300) $PN AD51
J 2
(-4585 6310);
DISPLAY 0.489362 (-4585 6310);
PAINT MONO (-4585 6310);
FORCEPROP 0 LASTPIN (-4625 6250) $PN AD52
J 2
(-4585 6260);
DISPLAY 0.489362 (-4585 6260);
PAINT MONO (-4585 6260);
FORCEPROP 0 LASTPIN (-4625 6200) $PN AD53
J 2
(-4585 6210);
DISPLAY 0.489362 (-4585 6210);
PAINT MONO (-4585 6210);
FORCEPROP 0 LASTPIN (-4625 6150) $PN AD57
J 2
(-4585 6160);
DISPLAY 0.489362 (-4585 6160);
PAINT MONO (-4585 6160);
FORCEPROP 0 LASTPIN (-4625 6100) $PN AD59
J 2
(-4585 6110);
DISPLAY 0.489362 (-4585 6110);
PAINT MONO (-4585 6110);
FORCEPROP 0 LASTPIN (-4625 6050) $PN AD61
J 2
(-4585 6060);
DISPLAY 0.489362 (-4585 6060);
PAINT MONO (-4585 6060);
FORCEPROP 0 LASTPIN (-4625 6000) $PN AD64
J 2
(-4585 6010);
DISPLAY 0.489362 (-4585 6010);
PAINT MONO (-4585 6010);
FORCEPROP 0 LASTPIN (-4625 5950) $PN AD66
J 2
(-4585 5960);
DISPLAY 0.489362 (-4585 5960);
PAINT MONO (-4585 5960);
FORCEPROP 0 LASTPIN (-4625 5900) $PN AD68
J 2
(-4585 5910);
DISPLAY 0.489362 (-4585 5910);
PAINT MONO (-4585 5910);
FORCEPROP 0 LASTPIN (-4625 5850) $PN AD71
J 2
(-4585 5860);
DISPLAY 0.489362 (-4585 5860);
PAINT MONO (-4585 5860);
FORCEPROP 0 LASTPIN (-4625 5800) $PN AD73
J 2
(-4585 5810);
DISPLAY 0.489362 (-4585 5810);
PAINT MONO (-4585 5810);
FORCEPROP 0 LASTPIN (-4625 5750) $PN AE1
J 2
(-4585 5760);
DISPLAY 0.489362 (-4585 5760);
PAINT MONO (-4585 5760);
FORCEPROP 0 LASTPIN (-4625 5700) $PN AE6
J 2
(-4585 5710);
DISPLAY 0.489362 (-4585 5710);
PAINT MONO (-4585 5710);
FORCEPROP 0 LASTPIN (-4625 5650) $PN AE8
J 2
(-4585 5660);
DISPLAY 0.489362 (-4585 5660);
PAINT MONO (-4585 5660);
FORCEPROP 0 LASTPIN (-4625 5600) $PN AE11
J 2
(-4585 5610);
DISPLAY 0.489362 (-4585 5610);
PAINT MONO (-4585 5610);
FORCEPROP 0 LASTPIN (-4625 5550) $PN AE13
J 2
(-4585 5560);
DISPLAY 0.489362 (-4585 5560);
PAINT MONO (-4585 5560);
FORCEPROP 0 LASTPIN (-4625 5500) $PN AE15
J 2
(-4585 5510);
DISPLAY 0.489362 (-4585 5510);
PAINT MONO (-4585 5510);
FORCEPROP 0 LASTPIN (-4625 5450) $PN AE18
J 2
(-4585 5460);
DISPLAY 0.489362 (-4585 5460);
PAINT MONO (-4585 5460);
FORCEPROP 0 LASTPIN (-4625 5400) $PN AE20
J 2
(-4585 5410);
DISPLAY 0.489362 (-4585 5410);
PAINT MONO (-4585 5410);
FORCEPROP 0 LASTPIN (-4625 5350) $PN AE22
J 2
(-4585 5360);
DISPLAY 0.489362 (-4585 5360);
PAINT MONO (-4585 5360);
FORCEPROP 0 LASTPIN (-4625 5300) $PN AE25
J 2
(-4585 5310);
DISPLAY 0.489362 (-4585 5310);
PAINT MONO (-4585 5310);
FORCEPROP 0 LASTPIN (-4625 5250) $PN AE28
J 2
(-4585 5260);
DISPLAY 0.489362 (-4585 5260);
PAINT MONO (-4585 5260);
FORCEPROP 0 LASTPIN (-4625 5200) $PN AE31
J 2
(-4585 5210);
DISPLAY 0.489362 (-4585 5210);
PAINT MONO (-4585 5210);
FORCEPROP 0 LASTPIN (-4625 5150) $PN AE34
J 2
(-4585 5160);
DISPLAY 0.489362 (-4585 5160);
PAINT MONO (-4585 5160);
FORCEPROP 0 LASTPIN (-4625 5100) $PN AE35
J 2
(-4585 5110);
DISPLAY 0.489362 (-4585 5110);
PAINT MONO (-4585 5110);
FORCEPROP 0 LASTPIN (-4625 5050) $PN AE36
J 2
(-4585 5060);
DISPLAY 0.489362 (-4585 5060);
PAINT MONO (-4585 5060);
FORCEPROP 0 LASTPIN (-4625 5000) $PN AE40
J 2
(-4585 5010);
DISPLAY 0.489362 (-4585 5010);
PAINT MONO (-4585 5010);
FORCEPROP 0 LASTPIN (-4625 4950) $PN AE41
J 2
(-4585 4960);
DISPLAY 0.489362 (-4585 4960);
PAINT MONO (-4585 4960);
FORCEPROP 0 LASTPIN (-4625 4900) $PN AE42
J 2
(-4585 4910);
DISPLAY 0.489362 (-4585 4910);
PAINT MONO (-4585 4910);
FORCEPROP 0 LASTPIN (-4625 4850) $PN AE45
J 2
(-4585 4860);
DISPLAY 0.489362 (-4585 4860);
PAINT MONO (-4585 4860);
FORCEPROP 0 LASTPIN (-4625 4800) $PN AE48
J 2
(-4585 4810);
DISPLAY 0.489362 (-4585 4810);
PAINT MONO (-4585 4810);
FORCEPROP 0 LASTPIN (-4625 4750) $PN AE51
J 2
(-4585 4760);
DISPLAY 0.489362 (-4585 4760);
PAINT MONO (-4585 4760);
FORCEPROP 0 LASTPIN (-4625 4700) $PN AE54
J 2
(-4585 4710);
DISPLAY 0.489362 (-4585 4710);
PAINT MONO (-4585 4710);
FORCEPROP 0 LASTPIN (-4625 4650) $PN AE56
J 2
(-4585 4660);
DISPLAY 0.489362 (-4585 4660);
PAINT MONO (-4585 4660);
FORCEPROP 0 LASTPIN (-4625 4600) $PN AE58
J 2
(-4585 4610);
DISPLAY 0.489362 (-4585 4610);
PAINT MONO (-4585 4610);
FORCEPROP 0 LASTPIN (-4625 4550) $PN AE61
J 2
(-4585 4560);
DISPLAY 0.489362 (-4585 4560);
PAINT MONO (-4585 4560);
FORCEPROP 0 LASTPIN (-4625 4500) $PN AE63
J 2
(-4585 4510);
DISPLAY 0.489362 (-4585 4510);
PAINT MONO (-4585 4510);
FORCEPROP 0 LASTPIN (-4625 4450) $PN AE65
J 2
(-4585 4460);
DISPLAY 0.489362 (-4585 4460);
PAINT MONO (-4585 4460);
FORCEPROP 0 LASTPIN (-4625 4400) $PN AE68
J 2
(-4585 4410);
DISPLAY 0.489362 (-4585 4410);
PAINT MONO (-4585 4410);
FORCEPROP 0 LASTPIN (-4625 4350) $PN AE70
J 2
(-4585 4360);
DISPLAY 0.489362 (-4585 4360);
PAINT MONO (-4585 4360);
FORCEPROP 0 LASTPIN (-4625 4300) $PN AE72
J 2
(-4585 4310);
DISPLAY 0.489362 (-4585 4310);
PAINT MONO (-4585 4310);
FORCEPROP 0 LASTPIN (-4625 4250) $PN AE75
J 2
(-4585 4260);
DISPLAY 0.489362 (-4585 4260);
PAINT MONO (-4585 4260);
FORCEPROP 0 LASTPIN (-4625 4200) $PN AF3
J 2
(-4585 4210);
DISPLAY 0.489362 (-4585 4210);
PAINT MONO (-4585 4210);
FORCEPROP 0 LASTPIN (-4625 4150) $PN AF8
J 2
(-4585 4160);
DISPLAY 0.489362 (-4585 4160);
PAINT MONO (-4585 4160);
FORCEPROP 0 LASTPIN (-4625 4100) $PN AF10
J 2
(-4585 4110);
DISPLAY 0.489362 (-4585 4110);
PAINT MONO (-4585 4110);
FORCEPROP 0 LASTPIN (-4625 4050) $PN AF15
J 2
(-4585 4060);
DISPLAY 0.489362 (-4585 4060);
PAINT MONO (-4585 4060);
FORCEPROP 0 LASTPIN (-4625 4000) $PN AF17
J 2
(-4585 4010);
DISPLAY 0.489362 (-4585 4010);
PAINT MONO (-4585 4010);
FORCEPROP 0 LASTPIN (-4625 3950) $PN AF22
J 2
(-4585 3960);
DISPLAY 0.489362 (-4585 3960);
PAINT MONO (-4585 3960);
FORCEPROP 0 LASTPIN (-4625 3900) $PN AF25
J 2
(-4585 3910);
DISPLAY 0.489362 (-4585 3910);
PAINT MONO (-4585 3910);
FORCEPROP 0 LASTPIN (-4625 3850) $PN AF28
J 2
(-4585 3860);
DISPLAY 0.489362 (-4585 3860);
PAINT MONO (-4585 3860);
FORCEPROP 0 LASTPIN (-4625 3800) $PN AF31
J 2
(-4585 3810);
DISPLAY 0.489362 (-4585 3810);
PAINT MONO (-4585 3810);
FORCEPROP 0 LASTPIN (-4625 3750) $PN AF34
J 2
(-4585 3760);
DISPLAY 0.489362 (-4585 3760);
PAINT MONO (-4585 3760);
FORCEPROP 0 LASTPIN (-4625 3700) $PN AF37
J 2
(-4585 3710);
DISPLAY 0.489362 (-4585 3710);
PAINT MONO (-4585 3710);
FORCEPROP 0 LASTPIN (-4625 3650) $PN AF39
J 2
(-4585 3660);
DISPLAY 0.489362 (-4585 3660);
PAINT MONO (-4585 3660);
FORCEPROP 0 LASTPIN (-4625 3600) $PN AF42
J 2
(-4585 3610);
DISPLAY 0.489362 (-4585 3610);
PAINT MONO (-4585 3610);
FORCEPROP 0 LASTPIN (-4625 3550) $PN AF45
J 2
(-4585 3560);
DISPLAY 0.489362 (-4585 3560);
PAINT MONO (-4585 3560);
FORCEPROP 0 LASTPIN (-4625 3500) $PN AF48
J 2
(-4585 3510);
DISPLAY 0.489362 (-4585 3510);
PAINT MONO (-4585 3510);
FORCEPROP 0 LASTPIN (-4625 3450) $PN AF51
J 2
(-4585 3460);
DISPLAY 0.489362 (-4585 3460);
PAINT MONO (-4585 3460);
FORCEPROP 0 LASTPIN (-4625 3400) $PN AF54
J 2
(-4585 3410);
DISPLAY 0.489362 (-4585 3410);
PAINT MONO (-4585 3410);
FORCEPROP 0 LASTPIN (-4625 3350) $PN AF59
J 2
(-4585 3360);
DISPLAY 0.489362 (-4585 3360);
PAINT MONO (-4585 3360);
FORCEPROP 0 LASTPIN (-4625 3300) $PN AF61
J 2
(-4585 3310);
DISPLAY 0.489362 (-4585 3310);
PAINT MONO (-4585 3310);
FORCEPROP 0 LASTPIN (-4625 3250) $PN AF66
J 2
(-4585 3260);
DISPLAY 0.489362 (-4585 3260);
PAINT MONO (-4585 3260);
FORCEPROP 0 LASTPIN (-4625 3200) $PN AF68
J 2
(-4585 3210);
DISPLAY 0.489362 (-4585 3210);
PAINT MONO (-4585 3210);
FORCEPROP 0 LASTPIN (-4625 3150) $PN AF73
J 2
(-4585 3160);
DISPLAY 0.489362 (-4585 3160);
PAINT MONO (-4585 3160);
FORCEPROP 0 LASTPIN (-4625 3100) $PN AG1
J 2
(-4585 3110);
DISPLAY 0.489362 (-4585 3110);
PAINT MONO (-4585 3110);
FORCEPROP 0 LASTPIN (-4625 3050) $PN AG4
J 2
(-4585 3060);
DISPLAY 0.489362 (-4585 3060);
PAINT MONO (-4585 3060);
FORCEPROP 0 LASTPIN (-4625 3000) $PN AG6
J 2
(-4585 3010);
DISPLAY 0.489362 (-4585 3010);
PAINT MONO (-4585 3010);
FORCEPROP 0 LASTPIN (-4625 2950) $PN AG8
J 2
(-4585 2960);
DISPLAY 0.489362 (-4585 2960);
PAINT MONO (-4585 2960);
FORCEPROP 0 LASTPIN (-4625 2900) $PN AG11
J 2
(-4585 2910);
DISPLAY 0.489362 (-4585 2910);
PAINT MONO (-4585 2910);
FORCEPROP 0 LASTPIN (-4625 2850) $PN AG13
J 2
(-4585 2860);
DISPLAY 0.489362 (-4585 2860);
PAINT MONO (-4585 2860);
FORCEPROP 0 LASTPIN (-4625 2800) $PN AG15
J 2
(-4585 2810);
DISPLAY 0.489362 (-4585 2810);
PAINT MONO (-4585 2810);
FORCEPROP 0 LASTPIN (-4625 2750) $PN AG18
J 2
(-4585 2760);
DISPLAY 0.489362 (-4585 2760);
PAINT MONO (-4585 2760);
FORCEPROP 0 LASTPIN (-4625 2700) $PN AG20
J 2
(-4585 2710);
DISPLAY 0.489362 (-4585 2710);
PAINT MONO (-4585 2710);
FORCEPROP 0 LASTPIN (-4625 2650) $PN AG22
J 2
(-4585 2660);
DISPLAY 0.489362 (-4585 2660);
PAINT MONO (-4585 2660);
FORCEPROP 0 LASTPIN (-4625 2600) $PN AG25
J 2
(-4585 2610);
DISPLAY 0.489362 (-4585 2610);
PAINT MONO (-4585 2610);
FORCEPROP 0 LASTPIN (-4625 2550) $PN AG28
J 2
(-4585 2560);
DISPLAY 0.489362 (-4585 2560);
PAINT MONO (-4585 2560);
FORCEPROP 0 LASTPIN (-4625 2500) $PN AG31
J 2
(-4585 2510);
DISPLAY 0.489362 (-4585 2510);
PAINT MONO (-4585 2510);
FORCEPROP 0 LASTPIN (-4625 2450) $PN AG34
J 2
(-4585 2460);
DISPLAY 0.489362 (-4585 2460);
PAINT MONO (-4585 2460);
FORCEPROP 0 LASTPIN (-4625 2400) $PN AG42
J 2
(-4585 2410);
DISPLAY 0.489362 (-4585 2410);
PAINT MONO (-4585 2410);
FORCEPROP 0 LASTPIN (-4625 2350) $PN AG45
J 2
(-4585 2360);
DISPLAY 0.489362 (-4585 2360);
PAINT MONO (-4585 2360);
FORCEPROP 0 LASTPIN (-4625 2300) $PN AG48
J 2
(-4585 2310);
DISPLAY 0.489362 (-4585 2310);
PAINT MONO (-4585 2310);
FORCEPROP 0 LASTPIN (-4625 2250) $PN AG51
J 2
(-4585 2260);
DISPLAY 0.489362 (-4585 2260);
PAINT MONO (-4585 2260);
FORCEPROP 0 LASTPIN (-4625 2200) $PN AG54
J 2
(-4585 2210);
DISPLAY 0.489362 (-4585 2210);
PAINT MONO (-4585 2210);
FORCEPROP 0 LASTPIN (-4625 2150) $PN AG56
J 2
(-4585 2160);
DISPLAY 0.489362 (-4585 2160);
PAINT MONO (-4585 2160);
FORCEPROP 0 LASTPIN (-4625 2100) $PN AG58
J 2
(-4585 2110);
DISPLAY 0.489362 (-4585 2110);
PAINT MONO (-4585 2110);
FORCEPROP 0 LASTPIN (-4625 2050) $PN AG61
J 2
(-4585 2060);
DISPLAY 0.489362 (-4585 2060);
PAINT MONO (-4585 2060);
FORCEPROP 0 LASTPIN (-4625 2000) $PN AG63
J 2
(-4585 2010);
DISPLAY 0.489362 (-4585 2010);
PAINT MONO (-4585 2010);
FORCEPROP 0 LASTPIN (-4625 1950) $PN AG65
J 2
(-4585 1960);
DISPLAY 0.489362 (-4585 1960);
PAINT MONO (-4585 1960);
FORCEPROP 0 LASTPIN (-4625 1900) $PN AG68
J 2
(-4585 1910);
DISPLAY 0.489362 (-4585 1910);
PAINT MONO (-4585 1910);
FORCEPROP 0 LASTPIN (-4625 1850) $PN AG70
J 2
(-4585 1860);
DISPLAY 0.489362 (-4585 1860);
PAINT MONO (-4585 1860);
FORCEPROP 0 LASTPIN (-4625 1800) $PN AG72
J 2
(-4585 1810);
DISPLAY 0.489362 (-4585 1810);
PAINT MONO (-4585 1810);
FORCEPROP 0 LASTPIN (-4625 1750) $PN AG75
J 2
(-4585 1760);
DISPLAY 0.489362 (-4585 1760);
PAINT MONO (-4585 1760);
FORCEPROP 0 LASTPIN (-4625 1700) $PN AH3
J 2
(-4585 1710);
DISPLAY 0.489362 (-4585 1710);
PAINT MONO (-4585 1710);
FORCEPROP 0 LASTPIN (-4625 1650) $PN AH5
J 2
(-4585 1660);
DISPLAY 0.489362 (-4585 1660);
PAINT MONO (-4585 1660);
FORCEPROP 0 LASTPIN (-4625 1600) $PN AH8
J 2
(-4585 1610);
DISPLAY 0.489362 (-4585 1610);
PAINT MONO (-4585 1610);
FORCEPROP 0 LASTPIN (-4625 1550) $PN AH10
J 2
(-4585 1560);
DISPLAY 0.489362 (-4585 1560);
PAINT MONO (-4585 1560);
FORCEPROP 0 LASTPIN (-4625 1500) $PN AH12
J 2
(-4585 1510);
DISPLAY 0.489362 (-4585 1510);
PAINT MONO (-4585 1510);
FORCEPROP 0 LASTPIN (-4625 1450) $PN AH15
J 2
(-4585 1460);
DISPLAY 0.489362 (-4585 1460);
PAINT MONO (-4585 1460);
FORCEPROP 0 LASTPIN (-4625 1400) $PN AH17
J 2
(-4585 1410);
DISPLAY 0.489362 (-4585 1410);
PAINT MONO (-4585 1410);
FORCEPROP 0 LASTPIN (-4625 1350) $PN AH19
J 2
(-4585 1360);
DISPLAY 0.489362 (-4585 1360);
PAINT MONO (-4585 1360);
FORCEPROP 0 LASTPIN (-4625 1300) $PN AH23
J 2
(-4585 1310);
DISPLAY 0.489362 (-4585 1310);
PAINT MONO (-4585 1310);
FORCEPROP 0 LASTPIN (-4625 1250) $PN AH24
J 2
(-4585 1260);
DISPLAY 0.489362 (-4585 1260);
PAINT MONO (-4585 1260);
FORCEPROP 0 LASTPIN (-4625 1200) $PN AH25
J 2
(-4585 1210);
DISPLAY 0.489362 (-4585 1210);
PAINT MONO (-4585 1210);
FORCEPROP 0 LASTPIN (-4625 1150) $PN AH26
J 2
(-4585 1160);
DISPLAY 0.489362 (-4585 1160);
PAINT MONO (-4585 1160);
FORCEPROP 0 LASTPIN (-4625 1100) $PN AH27
J 2
(-4585 1110);
DISPLAY 0.489362 (-4585 1110);
PAINT MONO (-4585 1110);
FORCEPROP 0 LASTPIN (-4625 1050) $PN AH28
J 2
(-4585 1060);
DISPLAY 0.489362 (-4585 1060);
PAINT MONO (-4585 1060);
FORCEPROP 0 LASTPIN (-4625 1000) $PN AH29
J 2
(-4585 1010);
DISPLAY 0.489362 (-4585 1010);
PAINT MONO (-4585 1010);
FORCEPROP 0 LASTPIN (-4625 950) $PN AH30
J 2
(-4585 960);
DISPLAY 0.489362 (-4585 960);
PAINT MONO (-4585 960);
FORCEPROP 0 LASTPIN (-4625 900) $PN AH31
J 2
(-4585 910);
DISPLAY 0.489362 (-4585 910);
PAINT MONO (-4585 910);
FORCEPROP 0 LASTPIN (-4625 850) $PN AH32
J 2
(-4585 860);
DISPLAY 0.489362 (-4585 860);
PAINT MONO (-4585 860);
FORCEPROP 0 LASTPIN (-4625 800) $PN AH34
J 2
(-4585 810);
DISPLAY 0.489362 (-4585 810);
PAINT MONO (-4585 810);
FORCEPROP 0 LASTPIN (-4625 750) $PN AH37
J 2
(-4585 760);
DISPLAY 0.489362 (-4585 760);
PAINT MONO (-4585 760);
FORCEPROP 0 LASTPIN (-4625 700) $PN AH39
J 2
(-4585 710);
DISPLAY 0.489362 (-4585 710);
PAINT MONO (-4585 710);
FORCEPROP 0 LASTPIN (-4625 650) $PN AH42
J 2
(-4585 660);
DISPLAY 0.489362 (-4585 660);
PAINT MONO (-4585 660);
FORCEPROP 0 LASTPIN (-4625 600) $PN AH43
J 2
(-4585 610);
DISPLAY 0.489362 (-4585 610);
PAINT MONO (-4585 610);
FORCEPROP 0 LASTPIN (-3525 6400) $PN AH44
J 0
(-3560 6410);
DISPLAY 0.489362 (-3560 6410);
PAINT MONO (-3560 6410);
FORCEPROP 0 LASTPIN (-3525 6350) $PN AH45
J 0
(-3560 6360);
DISPLAY 0.489362 (-3560 6360);
PAINT MONO (-3560 6360);
FORCEPROP 0 LASTPIN (-3525 6300) $PN AH46
J 0
(-3560 6310);
DISPLAY 0.489362 (-3560 6310);
PAINT MONO (-3560 6310);
FORCEPROP 0 LASTPIN (-3525 6250) $PN AH47
J 0
(-3560 6260);
DISPLAY 0.489362 (-3560 6260);
PAINT MONO (-3560 6260);
FORCEPROP 0 LASTPIN (-3525 6200) $PN AH48
J 0
(-3560 6210);
DISPLAY 0.489362 (-3560 6210);
PAINT MONO (-3560 6210);
FORCEPROP 0 LASTPIN (-3525 6150) $PN AH49
J 0
(-3560 6160);
DISPLAY 0.489362 (-3560 6160);
PAINT MONO (-3560 6160);
FORCEPROP 0 LASTPIN (-3525 6100) $PN AH50
J 0
(-3560 6110);
DISPLAY 0.489362 (-3560 6110);
PAINT MONO (-3560 6110);
FORCEPROP 0 LASTPIN (-3525 6050) $PN AH51
J 0
(-3560 6060);
DISPLAY 0.489362 (-3560 6060);
PAINT MONO (-3560 6060);
FORCEPROP 0 LASTPIN (-3525 6000) $PN AH52
J 0
(-3560 6010);
DISPLAY 0.489362 (-3560 6010);
PAINT MONO (-3560 6010);
FORCEPROP 0 LASTPIN (-3525 5950) $PN AH53
J 0
(-3560 5960);
DISPLAY 0.489362 (-3560 5960);
PAINT MONO (-3560 5960);
FORCEPROP 0 LASTPIN (-3525 5900) $PN AH57
J 0
(-3560 5910);
DISPLAY 0.489362 (-3560 5910);
PAINT MONO (-3560 5910);
FORCEPROP 0 LASTPIN (-3525 5850) $PN AH59
J 0
(-3560 5860);
DISPLAY 0.489362 (-3560 5860);
PAINT MONO (-3560 5860);
FORCEPROP 0 LASTPIN (-3525 5800) $PN AH61
J 0
(-3560 5810);
DISPLAY 0.489362 (-3560 5810);
PAINT MONO (-3560 5810);
FORCEPROP 0 LASTPIN (-3525 5750) $PN AH64
J 0
(-3560 5760);
DISPLAY 0.489362 (-3560 5760);
PAINT MONO (-3560 5760);
FORCEPROP 0 LASTPIN (-3525 5700) $PN AH66
J 0
(-3560 5710);
DISPLAY 0.489362 (-3560 5710);
PAINT MONO (-3560 5710);
FORCEPROP 0 LASTPIN (-3525 5650) $PN AH68
J 0
(-3560 5660);
DISPLAY 0.489362 (-3560 5660);
PAINT MONO (-3560 5660);
FORCEPROP 0 LASTPIN (-3525 5600) $PN AH71
J 0
(-3560 5610);
DISPLAY 0.489362 (-3560 5610);
PAINT MONO (-3560 5610);
FORCEPROP 0 LASTPIN (-3525 5550) $PN AH73
J 0
(-3560 5560);
DISPLAY 0.489362 (-3560 5560);
PAINT MONO (-3560 5560);
FORCEPROP 0 LASTPIN (-3525 5500) $PN AJ1
J 0
(-3560 5510);
DISPLAY 0.489362 (-3560 5510);
PAINT MONO (-3560 5510);
FORCEPROP 0 LASTPIN (-3525 5450) $PN AJ6
J 0
(-3560 5460);
DISPLAY 0.489362 (-3560 5460);
PAINT MONO (-3560 5460);
FORCEPROP 0 LASTPIN (-3525 5400) $PN AJ8
J 0
(-3560 5410);
DISPLAY 0.489362 (-3560 5410);
PAINT MONO (-3560 5410);
FORCEPROP 0 LASTPIN (-3525 5350) $PN AJ15
J 0
(-3560 5360);
DISPLAY 0.489362 (-3560 5360);
PAINT MONO (-3560 5360);
FORCEPROP 0 LASTPIN (-3525 5300) $PN AJ20
J 0
(-3560 5310);
DISPLAY 0.489362 (-3560 5310);
PAINT MONO (-3560 5310);
FORCEPROP 0 LASTPIN (-3525 5250) $PN AJ22
J 0
(-3560 5260);
DISPLAY 0.489362 (-3560 5260);
PAINT MONO (-3560 5260);
FORCEPROP 0 LASTPIN (-3525 5200) $PN AJ25
J 0
(-3560 5210);
DISPLAY 0.489362 (-3560 5210);
PAINT MONO (-3560 5210);
FORCEPROP 0 LASTPIN (-3525 5150) $PN AJ28
J 0
(-3560 5160);
DISPLAY 0.489362 (-3560 5160);
PAINT MONO (-3560 5160);
FORCEPROP 0 LASTPIN (-3525 5100) $PN AJ31
J 0
(-3560 5110);
DISPLAY 0.489362 (-3560 5110);
PAINT MONO (-3560 5110);
FORCEPROP 0 LASTPIN (-3525 5050) $PN AJ34
J 0
(-3560 5060);
DISPLAY 0.489362 (-3560 5060);
PAINT MONO (-3560 5060);
FORCEPROP 0 LASTPIN (-3525 5000) $PN AJ35
J 0
(-3560 5010);
DISPLAY 0.489362 (-3560 5010);
PAINT MONO (-3560 5010);
FORCEPROP 0 LASTPIN (-3525 4950) $PN AJ36
J 0
(-3560 4960);
DISPLAY 0.489362 (-3560 4960);
PAINT MONO (-3560 4960);
FORCEPROP 0 LASTPIN (-3525 4900) $PN AJ40
J 0
(-3560 4910);
DISPLAY 0.489362 (-3560 4910);
PAINT MONO (-3560 4910);
FORCEPROP 0 LASTPIN (-3525 4850) $PN AJ41
J 0
(-3560 4860);
DISPLAY 0.489362 (-3560 4860);
PAINT MONO (-3560 4860);
FORCEPROP 0 LASTPIN (-3525 4800) $PN AJ42
J 0
(-3560 4810);
DISPLAY 0.489362 (-3560 4810);
PAINT MONO (-3560 4810);
FORCEPROP 0 LASTPIN (-3525 4750) $PN AJ45
J 0
(-3560 4760);
DISPLAY 0.489362 (-3560 4760);
PAINT MONO (-3560 4760);
FORCEPROP 0 LASTPIN (-3525 4700) $PN AJ48
J 0
(-3560 4710);
DISPLAY 0.489362 (-3560 4710);
PAINT MONO (-3560 4710);
FORCEPROP 0 LASTPIN (-3525 4650) $PN AJ51
J 0
(-3560 4660);
DISPLAY 0.489362 (-3560 4660);
PAINT MONO (-3560 4660);
FORCEPROP 0 LASTPIN (-3525 4600) $PN AJ54
J 0
(-3560 4610);
DISPLAY 0.489362 (-3560 4610);
PAINT MONO (-3560 4610);
FORCEPROP 0 LASTPIN (-3525 4550) $PN AJ56
J 0
(-3560 4560);
DISPLAY 0.489362 (-3560 4560);
PAINT MONO (-3560 4560);
FORCEPROP 0 LASTPIN (-3525 4500) $PN AJ61
J 0
(-3560 4510);
DISPLAY 0.489362 (-3560 4510);
PAINT MONO (-3560 4510);
FORCEPROP 0 LASTPIN (-3525 4450) $PN AJ63
J 0
(-3560 4460);
DISPLAY 0.489362 (-3560 4460);
PAINT MONO (-3560 4460);
FORCEPROP 0 LASTPIN (-3525 4400) $PN AJ68
J 0
(-3560 4410);
DISPLAY 0.489362 (-3560 4410);
PAINT MONO (-3560 4410);
FORCEPROP 0 LASTPIN (-3525 4350) $PN AJ70
J 0
(-3560 4360);
DISPLAY 0.489362 (-3560 4360);
PAINT MONO (-3560 4360);
FORCEPROP 0 LASTPIN (-3525 4300) $PN AJ75
J 0
(-3560 4310);
DISPLAY 0.489362 (-3560 4310);
PAINT MONO (-3560 4310);
FORCEPROP 0 LASTPIN (-3525 4250) $PN AK3
J 0
(-3560 4260);
DISPLAY 0.489362 (-3560 4260);
PAINT MONO (-3560 4260);
FORCEPROP 0 LASTPIN (-3525 4200) $PN AK5
J 0
(-3560 4210);
DISPLAY 0.489362 (-3560 4210);
PAINT MONO (-3560 4210);
FORCEPROP 0 LASTPIN (-3525 4150) $PN AK8
J 0
(-3560 4160);
DISPLAY 0.489362 (-3560 4160);
PAINT MONO (-3560 4160);
FORCEPROP 0 LASTPIN (-3525 4100) $PN AK10
J 0
(-3560 4110);
DISPLAY 0.489362 (-3560 4110);
PAINT MONO (-3560 4110);
FORCEPROP 0 LASTPIN (-3525 4050) $PN AK12
J 0
(-3560 4060);
DISPLAY 0.489362 (-3560 4060);
PAINT MONO (-3560 4060);
FORCEPROP 0 LASTPIN (-3525 4000) $PN AK15
J 0
(-3560 4010);
DISPLAY 0.489362 (-3560 4010);
PAINT MONO (-3560 4010);
FORCEPROP 0 LASTPIN (-3525 3950) $PN AK17
J 0
(-3560 3960);
DISPLAY 0.489362 (-3560 3960);
PAINT MONO (-3560 3960);
FORCEPROP 0 LASTPIN (-3525 3900) $PN AK19
J 0
(-3560 3910);
DISPLAY 0.489362 (-3560 3910);
PAINT MONO (-3560 3910);
FORCEPROP 0 LASTPIN (-3525 3850) $PN AK22
J 0
(-3560 3860);
DISPLAY 0.489362 (-3560 3860);
PAINT MONO (-3560 3860);
FORCEPROP 0 LASTPIN (-3525 3800) $PN AK25
J 0
(-3560 3810);
DISPLAY 0.489362 (-3560 3810);
PAINT MONO (-3560 3810);
FORCEPROP 0 LASTPIN (-3525 3750) $PN AK28
J 0
(-3560 3760);
DISPLAY 0.489362 (-3560 3760);
PAINT MONO (-3560 3760);
FORCEPROP 0 LASTPIN (-3525 3700) $PN AK31
J 0
(-3560 3710);
DISPLAY 0.489362 (-3560 3710);
PAINT MONO (-3560 3710);
FORCEPROP 0 LASTPIN (-3525 3650) $PN AK34
J 0
(-3560 3660);
DISPLAY 0.489362 (-3560 3660);
PAINT MONO (-3560 3660);
FORCEPROP 0 LASTPIN (-3525 3600) $PN AK37
J 0
(-3560 3610);
DISPLAY 0.489362 (-3560 3610);
PAINT MONO (-3560 3610);
FORCEPROP 0 LASTPIN (-3525 3550) $PN AK39
J 0
(-3560 3560);
DISPLAY 0.489362 (-3560 3560);
PAINT MONO (-3560 3560);
FORCEPROP 0 LASTPIN (-3525 3500) $PN AK42
J 0
(-3560 3510);
DISPLAY 0.489362 (-3560 3510);
PAINT MONO (-3560 3510);
FORCEPROP 0 LASTPIN (-3525 3450) $PN AK45
J 0
(-3560 3460);
DISPLAY 0.489362 (-3560 3460);
PAINT MONO (-3560 3460);
FORCEPROP 0 LASTPIN (-3525 3400) $PN AK48
J 0
(-3560 3410);
DISPLAY 0.489362 (-3560 3410);
PAINT MONO (-3560 3410);
FORCEPROP 0 LASTPIN (-3525 3350) $PN AK51
J 0
(-3560 3360);
DISPLAY 0.489362 (-3560 3360);
PAINT MONO (-3560 3360);
FORCEPROP 0 LASTPIN (-3525 3300) $PN AK54
J 0
(-3560 3310);
DISPLAY 0.489362 (-3560 3310);
PAINT MONO (-3560 3310);
FORCEPROP 0 LASTPIN (-3525 3250) $PN AK57
J 0
(-3560 3260);
DISPLAY 0.489362 (-3560 3260);
PAINT MONO (-3560 3260);
FORCEPROP 0 LASTPIN (-3525 3200) $PN AK59
J 0
(-3560 3210);
DISPLAY 0.489362 (-3560 3210);
PAINT MONO (-3560 3210);
FORCEPROP 0 LASTPIN (-3525 3150) $PN AK61
J 0
(-3560 3160);
DISPLAY 0.489362 (-3560 3160);
PAINT MONO (-3560 3160);
FORCEPROP 0 LASTPIN (-3525 3100) $PN AK64
J 0
(-3560 3110);
DISPLAY 0.489362 (-3560 3110);
PAINT MONO (-3560 3110);
FORCEPROP 0 LASTPIN (-3525 3050) $PN AK66
J 0
(-3560 3060);
DISPLAY 0.489362 (-3560 3060);
PAINT MONO (-3560 3060);
FORCEPROP 0 LASTPIN (-3525 3000) $PN AK68
J 0
(-3560 3010);
DISPLAY 0.489362 (-3560 3010);
PAINT MONO (-3560 3010);
FORCEPROP 0 LASTPIN (-3525 2950) $PN AK71
J 0
(-3560 2960);
DISPLAY 0.489362 (-3560 2960);
PAINT MONO (-3560 2960);
FORCEPROP 0 LASTPIN (-3525 2900) $PN AK73
J 0
(-3560 2910);
DISPLAY 0.489362 (-3560 2910);
PAINT MONO (-3560 2910);
FORCEPROP 0 LASTPIN (-3525 2850) $PN AL1
J 0
(-3560 2860);
DISPLAY 0.489362 (-3560 2860);
PAINT MONO (-3560 2860);
FORCEPROP 0 LASTPIN (-3525 2800) $PN AL4
J 0
(-3560 2810);
DISPLAY 0.489362 (-3560 2810);
PAINT MONO (-3560 2810);
FORCEPROP 0 LASTPIN (-3525 2750) $PN AL6
J 0
(-3560 2760);
DISPLAY 0.489362 (-3560 2760);
PAINT MONO (-3560 2760);
FORCEPROP 0 LASTPIN (-3525 2700) $PN AL8
J 0
(-3560 2710);
DISPLAY 0.489362 (-3560 2710);
PAINT MONO (-3560 2710);
FORCEPROP 0 LASTPIN (-3525 2650) $PN AL11
J 0
(-3560 2660);
DISPLAY 0.489362 (-3560 2660);
PAINT MONO (-3560 2660);
FORCEPROP 0 LASTPIN (-3525 2600) $PN AL13
J 0
(-3560 2610);
DISPLAY 0.489362 (-3560 2610);
PAINT MONO (-3560 2610);
FORCEPROP 0 LASTPIN (-3525 2550) $PN AL15
J 0
(-3560 2560);
DISPLAY 0.489362 (-3560 2560);
PAINT MONO (-3560 2560);
FORCEPROP 0 LASTPIN (-3525 2500) $PN AL18
J 0
(-3560 2510);
DISPLAY 0.489362 (-3560 2510);
PAINT MONO (-3560 2510);
FORCEPROP 0 LASTPIN (-3525 2450) $PN AL20
J 0
(-3560 2460);
DISPLAY 0.489362 (-3560 2460);
PAINT MONO (-3560 2460);
FORCEPROP 0 LASTPIN (-3525 2400) $PN AL22
J 0
(-3560 2410);
DISPLAY 0.489362 (-3560 2410);
PAINT MONO (-3560 2410);
FORCEPROP 0 LASTPIN (-3525 2350) $PN AL25
J 0
(-3560 2360);
DISPLAY 0.489362 (-3560 2360);
PAINT MONO (-3560 2360);
FORCEPROP 0 LASTPIN (-3525 2300) $PN AL28
J 0
(-3560 2310);
DISPLAY 0.489362 (-3560 2310);
PAINT MONO (-3560 2310);
FORCEPROP 0 LASTPIN (-3525 2250) $PN AL31
J 0
(-3560 2260);
DISPLAY 0.489362 (-3560 2260);
PAINT MONO (-3560 2260);
FORCEPROP 0 LASTPIN (-3525 2200) $PN AL34
J 0
(-3560 2210);
DISPLAY 0.489362 (-3560 2210);
PAINT MONO (-3560 2210);
FORCEPROP 0 LASTPIN (-3525 2150) $PN AL42
J 0
(-3560 2160);
DISPLAY 0.489362 (-3560 2160);
PAINT MONO (-3560 2160);
FORCEPROP 0 LASTPIN (-3525 2100) $PN AL45
J 0
(-3560 2110);
DISPLAY 0.489362 (-3560 2110);
PAINT MONO (-3560 2110);
FORCEPROP 0 LASTPIN (-3525 2050) $PN AL48
J 0
(-3560 2060);
DISPLAY 0.489362 (-3560 2060);
PAINT MONO (-3560 2060);
FORCEPROP 0 LASTPIN (-3525 2000) $PN AL51
J 0
(-3560 2010);
DISPLAY 0.489362 (-3560 2010);
PAINT MONO (-3560 2010);
FORCEPROP 0 LASTPIN (-3525 1950) $PN AL54
J 0
(-3560 1960);
DISPLAY 0.489362 (-3560 1960);
PAINT MONO (-3560 1960);
FORCEPROP 0 LASTPIN (-3525 1900) $PN AL56
J 0
(-3560 1910);
DISPLAY 0.489362 (-3560 1910);
PAINT MONO (-3560 1910);
FORCEPROP 0 LASTPIN (-3525 1850) $PN AL58
J 0
(-3560 1860);
DISPLAY 0.489362 (-3560 1860);
PAINT MONO (-3560 1860);
FORCEPROP 0 LASTPIN (-3525 1800) $PN AL61
J 0
(-3560 1810);
DISPLAY 0.489362 (-3560 1810);
PAINT MONO (-3560 1810);
FORCEPROP 0 LASTPIN (-3525 1750) $PN AL63
J 0
(-3560 1760);
DISPLAY 0.489362 (-3560 1760);
PAINT MONO (-3560 1760);
FORCEPROP 0 LASTPIN (-3525 1700) $PN AL65
J 0
(-3560 1710);
DISPLAY 0.489362 (-3560 1710);
PAINT MONO (-3560 1710);
FORCEPROP 0 LASTPIN (-3525 1650) $PN AL68
J 0
(-3560 1660);
DISPLAY 0.489362 (-3560 1660);
PAINT MONO (-3560 1660);
FORCEPROP 0 LASTPIN (-3525 1600) $PN AL70
J 0
(-3560 1610);
DISPLAY 0.489362 (-3560 1610);
PAINT MONO (-3560 1610);
FORCEPROP 0 LASTPIN (-3525 1550) $PN AL72
J 0
(-3560 1560);
DISPLAY 0.489362 (-3560 1560);
PAINT MONO (-3560 1560);
FORCEPROP 0 LASTPIN (-3525 1500) $PN AL75
J 0
(-3560 1510);
DISPLAY 0.489362 (-3560 1510);
PAINT MONO (-3560 1510);
FORCEPROP 0 LASTPIN (-3525 1450) $PN AM3
J 0
(-3560 1460);
DISPLAY 0.489362 (-3560 1460);
PAINT MONO (-3560 1460);
FORCEPROP 0 LASTPIN (-3525 1400) $PN AM8
J 0
(-3560 1410);
DISPLAY 0.489362 (-3560 1410);
PAINT MONO (-3560 1410);
FORCEPROP 0 LASTPIN (-3525 1350) $PN AM10
J 0
(-3560 1360);
DISPLAY 0.489362 (-3560 1360);
PAINT MONO (-3560 1360);
FORCEPROP 0 LASTPIN (-3525 1300) $PN AM15
J 0
(-3560 1310);
DISPLAY 0.489362 (-3560 1310);
PAINT MONO (-3560 1310);
FORCEPROP 0 LASTPIN (-3525 1250) $PN AM17
J 0
(-3560 1260);
DISPLAY 0.489362 (-3560 1260);
PAINT MONO (-3560 1260);
FORCEPROP 0 LASTPIN (-3525 1200) $PN AM23
J 0
(-3560 1210);
DISPLAY 0.489362 (-3560 1210);
PAINT MONO (-3560 1210);
FORCEPROP 0 LASTPIN (-3525 1150) $PN AM24
J 0
(-3560 1160);
DISPLAY 0.489362 (-3560 1160);
PAINT MONO (-3560 1160);
FORCEPROP 0 LASTPIN (-3525 1100) $PN AM25
J 0
(-3560 1110);
DISPLAY 0.489362 (-3560 1110);
PAINT MONO (-3560 1110);
FORCEPROP 0 LASTPIN (-3525 1050) $PN AM26
J 0
(-3560 1060);
DISPLAY 0.489362 (-3560 1060);
PAINT MONO (-3560 1060);
FORCEPROP 0 LASTPIN (-3525 1000) $PN AM27
J 0
(-3560 1010);
DISPLAY 0.489362 (-3560 1010);
PAINT MONO (-3560 1010);
FORCEPROP 0 LASTPIN (-3525 950) $PN AM28
J 0
(-3560 960);
DISPLAY 0.489362 (-3560 960);
PAINT MONO (-3560 960);
FORCEPROP 0 LASTPIN (-3525 900) $PN AM29
J 0
(-3560 910);
DISPLAY 0.489362 (-3560 910);
PAINT MONO (-3560 910);
FORCEPROP 0 LASTPIN (-3525 850) $PN AM30
J 0
(-3560 860);
DISPLAY 0.489362 (-3560 860);
PAINT MONO (-3560 860);
FORCEPROP 0 LASTPIN (-3525 800) $PN AM31
J 0
(-3560 810);
DISPLAY 0.489362 (-3560 810);
PAINT MONO (-3560 810);
FORCEPROP 0 LASTPIN (-3525 750) $PN AM32
J 0
(-3560 760);
DISPLAY 0.489362 (-3560 760);
PAINT MONO (-3560 760);
FORCEPROP 0 LASTPIN (-3525 700) $PN AM33
J 0
(-3560 710);
DISPLAY 0.489362 (-3560 710);
PAINT MONO (-3560 710);
FORCEPROP 0 LASTPIN (-3525 650) $PN AM34
J 0
(-3560 660);
DISPLAY 0.489362 (-3560 660);
PAINT MONO (-3560 660);
FORCEPROP 0 LASTPIN (-3525 600) $PN AM39
J 0
(-3560 610);
DISPLAY 0.489362 (-3560 610);
PAINT MONO (-3560 610);
FORCEPROP 2 LAST PART_TYPE SMLF
J 0
(-4675 6680);
DISPLAY 1.021277 (-4675 6680);
FORCEPROP 1 LAST MATERIAL IO
J 0
(-4470 6582);
DISPLAY 0.489362 (-4470 6582);
PAINT SKYBLUE (-4470 6582);
FORCEPROP 2 LAST VALUE SOCKET6096_13568-001
J 0
(-4475 6625);
DISPLAY 0.489362 (-4475 6625);
PAINT SKYBLUE (-4475 6625);
FORCEPROP 1 LAST PART_NUMBER DGA^6000030
J 0
(-4475 6700);
DISPLAY 0.489362 (-4475 6700);
PAINT SKYBLUE (-4475 6700);
FORCEPROP 2 LAST CDS_LIB pure_quanta
J 0
(-4075 3500);
DISPLAY INVISIBLE (-4075 3500);
FORCEPROP 1 LAST CDS_LMAN_SYM_OUTLINE -400,3050,400,-3050
J 0
(-4075 3500);
DISPLAY 0.468085 (-4075 3500);
PAINT GREEN (-4075 3500);
DISPLAY INVISIBLE (-4075 3500);
FORCEPROP 1 LAST NEEDS_NO_SIZE TRUE
J 0
(-4075 3500);
DISPLAY 0.723404 (-4075 3500);
PAINT GREEN (-4075 3500);
DISPLAY INVISIBLE (-4075 3500);
FORCEPROP 1 LAST PATH I9
J 0
(-4075 3500);
DISPLAY 0.723404 (-4075 3500);
PAINT GREEN (-4075 3500);
DISPLAY INVISIBLE (-4075 3500);
FORCEADD QUANTA_TITLE_BLOCK_C..1
(-100 100);
FORCEPROP 0 LAST CDS_CON_LAST_MODIFIED Fri Mar 11 14:52:41 2022
J 0
(-1985 115);
DISPLAY INVISIBLE (-1985 115);
FORCEPROP 1 LAST CUSTOM_TXT_CDS <CON_LAST_MODIFIED>
J 0
(-1985 115);
DISPLAY 0.978723 (-1985 115);
FORCEPROP 2 LAST CUSTOM_TXT_CDS <XR_PAGE_TITLE>
J 0
(-7990 5350);
DISPLAY 0.638298 (-7990 5350);
PAINT PINK (-7990 5350);
DISPLAY INVISIBLE (-7990 5350);
FORCEPROP 1 LAST CUSTOM_TXT_CDS <NAME_2>
J 0
(-3275 150);
FORCEPROP 1 LAST CUSTOM_TXT_CDS <NAME_1>
J 0
(-3275 275);
FORCEPROP 1 LAST CUSTOM_TXT_CDS <Q_NUMBER>
J 0
(-1503 203);
DISPLAY 1.212766 (-1503 203);
FORCEPROP 1 LAST CUSTOM_TXT_CDS <Q_PROJ>
J 0
(-2482 202);
DISPLAY 1.212766 (-2482 202);
FORCEPROP 1 LAST CUSTOM_TXT_CDS <Q_REV>
J 0
(-284 203);
DISPLAY 1.212766 (-284 203);
FORCEPROP 1 LAST CUSTOM_TXT_CDS <CON_PAGE_NUM> OF <CON_TOTAL_PAGES>
J 0
(-546 118);
DISPLAY 0.978723 (-546 118);
FORCEPROP 1 LAST Q_TITLE CPU1 VSS 1/3
J 0
(-9400 175);
DISPLAY 2.446809 (-9400 175);
PAINT GREEN (-9400 175);
FORCEPROP 1 LAST Q_DEPT BU9
J 1
(-3863 149);
DISPLAY 1.957447 (-3863 149);
PAINT GREEN (-3863 149);
FORCEPROP 2 LAST PAGE_BORDER TRUE
J 0
(-7990 5350);
DISPLAY 0.638298 (-7990 5350);
PAINT PINK (-7990 5350);
DISPLAY INVISIBLE (-7990 5350);
FORCEPROP 1 LAST CDS_LMAN_SYM_OUTLINE -9475,6775,100,-125
J 0
(-100 100);
DISPLAY 0.468085 (-100 100);
PAINT GREEN (-100 100);
DISPLAY INVISIBLE (-100 100);
FORCEPROP 2 LAST CDS_LIB pure_quanta
J 0
(-100 100);
DISPLAY INVISIBLE (-100 100);
FORCEPROP 1 LAST COMMENT_BODY TRUE
J 0
(-88 87);
DISPLAY 0.978723 (-88 87);
PAINT GREEN (-88 87);
DISPLAY INVISIBLE (-88 87);
FORCEPROP 2 LAST CDS_XR_PAGE_TITLE CR-58 : @T6G_MB_LIB.T6G(SCH_1):PAGE58
J 0
(-7990 5350);
DISPLAY 0.638298 (-7990 5350);
PAINT PINK (-7990 5350);
DISPLAY INVISIBLE (-7990 5350);
WIRE 16 -1 (-9250 475)(-9125 475);
WIRE 16 -1 (-9250 525)(-9250 475);
WIRE 16 -1 (-9250 475)(-9250 425);
WIRE 16 -1 (-9250 525)(-9125 525);
WIRE 16 -1 (-9250 575)(-9250 525);
WIRE 16 -1 (-9125 575)(-9250 575);
WIRE 16 -1 (-9250 625)(-9250 575);
WIRE 16 -1 (-9125 625)(-9250 625);
WIRE 16 -1 (-9250 675)(-9250 625);
WIRE 16 -1 (-9125 675)(-9250 675);
WIRE 16 -1 (-9250 725)(-9250 675);
WIRE 16 -1 (-9125 725)(-9250 725);
WIRE 16 -1 (-9250 775)(-9250 725);
WIRE 16 -1 (-9125 775)(-9250 775);
WIRE 16 -1 (-9250 825)(-9250 775);
WIRE 16 -1 (-9125 825)(-9250 825);
WIRE 16 -1 (-9250 875)(-9250 825);
WIRE 16 -1 (-9125 875)(-9250 875);
WIRE 16 -1 (-9250 925)(-9250 875);
WIRE 16 -1 (-9125 925)(-9250 925);
WIRE 16 -1 (-9250 975)(-9250 925);
WIRE 16 -1 (-9250 975)(-9125 975);
WIRE 16 -1 (-9250 1025)(-9250 975);
WIRE 16 -1 (-9250 1025)(-9125 1025);
WIRE 16 -1 (-9250 1075)(-9250 1025);
WIRE 16 -1 (-9250 1075)(-9125 1075);
WIRE 16 -1 (-9250 1125)(-9250 1075);
WIRE 16 -1 (-9250 1125)(-9125 1125);
WIRE 16 -1 (-9250 1175)(-9250 1125);
WIRE 16 -1 (-9250 1175)(-9125 1175);
WIRE 16 -1 (-9250 1225)(-9250 1175);
WIRE 16 -1 (-9250 1225)(-9125 1225);
WIRE 16 -1 (-9250 1275)(-9250 1225);
WIRE 16 -1 (-9125 1275)(-9250 1275);
WIRE 16 -1 (-9250 1325)(-9250 1275);
WIRE 16 -1 (-9125 1325)(-9250 1325);
WIRE 16 -1 (-9250 1375)(-9250 1325);
WIRE 16 -1 (-9250 1375)(-9125 1375);
WIRE 16 -1 (-9250 1425)(-9250 1375);
WIRE 16 -1 (-9250 1425)(-9125 1425);
WIRE 16 -1 (-9250 1475)(-9250 1425);
WIRE 16 -1 (-9250 1475)(-9125 1475);
WIRE 16 -1 (-9250 1525)(-9250 1475);
WIRE 16 -1 (-9250 1525)(-9125 1525);
WIRE 16 -1 (-9250 1575)(-9250 1525);
WIRE 16 -1 (-9250 1575)(-9125 1575);
WIRE 16 -1 (-9250 1625)(-9250 1575);
WIRE 16 -1 (-9250 1625)(-9125 1625);
WIRE 16 -1 (-9250 1675)(-9250 1625);
WIRE 16 -1 (-9125 1675)(-9250 1675);
WIRE 16 -1 (-9250 1725)(-9250 1675);
WIRE 16 -1 (-9125 1725)(-9250 1725);
WIRE 16 -1 (-9250 1775)(-9250 1725);
WIRE 16 -1 (-9250 1775)(-9125 1775);
WIRE 16 -1 (-9250 1825)(-9250 1775);
WIRE 16 -1 (-9250 1825)(-9125 1825);
WIRE 16 -1 (-9250 1875)(-9250 1825);
WIRE 16 -1 (-9250 1875)(-9125 1875);
WIRE 16 -1 (-9250 1925)(-9250 1875);
WIRE 16 -1 (-9250 1925)(-9125 1925);
WIRE 16 -1 (-9250 1975)(-9250 1925);
WIRE 16 -1 (-9250 1975)(-9125 1975);
WIRE 16 -1 (-9250 2025)(-9250 1975);
WIRE 16 -1 (-9250 2075)(-9250 2025);
WIRE 16 -1 (-9250 2025)(-9125 2025);
WIRE 16 -1 (-9125 2075)(-9250 2075);
WIRE 16 -1 (-9250 2125)(-9250 2075);
WIRE 16 -1 (-9125 2125)(-9250 2125);
WIRE 16 -1 (-9250 2175)(-9250 2125);
WIRE 16 -1 (-9250 2175)(-9125 2175);
WIRE 16 -1 (-9250 2225)(-9250 2175);
WIRE 16 -1 (-9250 2225)(-9125 2225);
WIRE 16 -1 (-9250 2275)(-9250 2225);
WIRE 16 -1 (-9250 2275)(-9125 2275);
WIRE 16 -1 (-9250 2325)(-9250 2275);
WIRE 16 -1 (-9250 2325)(-9125 2325);
WIRE 16 -1 (-9250 2375)(-9250 2325);
WIRE 16 -1 (-9250 2375)(-9125 2375);
WIRE 16 -1 (-9250 2425)(-9250 2375);
WIRE 16 -1 (-9250 2425)(-9125 2425);
WIRE 16 -1 (-9250 2475)(-9250 2425);
WIRE 16 -1 (-9125 2475)(-9250 2475);
WIRE 16 -1 (-9250 2525)(-9250 2475);
WIRE 16 -1 (-9125 2525)(-9250 2525);
WIRE 16 -1 (-9250 2575)(-9250 2525);
WIRE 16 -1 (-9250 2575)(-9125 2575);
WIRE 16 -1 (-9250 2625)(-9250 2575);
WIRE 16 -1 (-9250 2625)(-9125 2625);
WIRE 16 -1 (-9250 2675)(-9250 2625);
WIRE 16 -1 (-9250 2675)(-9125 2675);
WIRE 16 -1 (-9250 2725)(-9250 2675);
WIRE 16 -1 (-9250 2725)(-9125 2725);
WIRE 16 -1 (-9250 2775)(-9250 2725);
WIRE 16 -1 (-9250 2775)(-9125 2775);
WIRE 16 -1 (-9250 2825)(-9250 2775);
WIRE 16 -1 (-9250 2825)(-9125 2825);
WIRE 16 -1 (-9250 2875)(-9250 2825);
WIRE 16 -1 (-9125 2875)(-9250 2875);
WIRE 16 -1 (-9250 2925)(-9250 2875);
WIRE 16 -1 (-9125 2925)(-9250 2925);
WIRE 16 -1 (-9250 2975)(-9250 2925);
WIRE 16 -1 (-9250 2975)(-9125 2975);
WIRE 16 -1 (-9250 3025)(-9250 2975);
WIRE 16 -1 (-9250 3025)(-9125 3025);
WIRE 16 -1 (-9250 3075)(-9250 3025);
WIRE 16 -1 (-9250 3075)(-9125 3075);
WIRE 16 -1 (-9250 3125)(-9250 3075);
WIRE 16 -1 (-9250 3125)(-9125 3125);
WIRE 16 -1 (-9250 3175)(-9250 3125);
WIRE 16 -1 (-9250 3175)(-9125 3175);
WIRE 16 -1 (-9250 3225)(-9250 3175);
WIRE 16 -1 (-9250 3225)(-9125 3225);
WIRE 16 -1 (-9250 3275)(-9250 3225);
WIRE 16 -1 (-9125 3275)(-9250 3275);
WIRE 16 -1 (-9250 3325)(-9250 3275);
WIRE 16 -1 (-9125 3325)(-9250 3325);
WIRE 16 -1 (-9250 3375)(-9250 3325);
WIRE 16 -1 (-9250 3375)(-9125 3375);
WIRE 16 -1 (-9250 3425)(-9250 3375);
WIRE 16 -1 (-9250 3425)(-9125 3425);
WIRE 16 -1 (-9250 3475)(-9250 3425);
WIRE 16 -1 (-9250 3475)(-9125 3475);
WIRE 16 -1 (-9250 3525)(-9250 3475);
WIRE 16 -1 (-9250 3525)(-9125 3525);
WIRE 16 -1 (-9250 3575)(-9250 3525);
WIRE 16 -1 (-9250 3575)(-9125 3575);
WIRE 16 -1 (-9250 3625)(-9250 3575);
WIRE 16 -1 (-9250 3625)(-9125 3625);
WIRE 16 -1 (-9250 3675)(-9250 3625);
WIRE 16 -1 (-9125 3675)(-9250 3675);
WIRE 16 -1 (-9250 3725)(-9250 3675);
WIRE 16 -1 (-9125 3725)(-9250 3725);
WIRE 16 -1 (-9250 3775)(-9250 3725);
WIRE 16 -1 (-9250 3775)(-9125 3775);
WIRE 16 -1 (-9250 3825)(-9250 3775);
WIRE 16 -1 (-9250 3825)(-9125 3825);
WIRE 16 -1 (-9250 3875)(-9250 3825);
WIRE 16 -1 (-9250 3875)(-9125 3875);
WIRE 16 -1 (-9250 3925)(-9250 3875);
WIRE 16 -1 (-9250 3925)(-9125 3925);
WIRE 16 -1 (-9250 3975)(-9250 3925);
WIRE 16 -1 (-9250 3975)(-9125 3975);
WIRE 16 -1 (-9250 4025)(-9250 3975);
WIRE 16 -1 (-9250 4025)(-9125 4025);
WIRE 16 -1 (-9250 4075)(-9250 4025);
WIRE 16 -1 (-9250 4125)(-9250 4075);
WIRE 16 -1 (-9125 4075)(-9250 4075);
WIRE 16 -1 (-9125 4125)(-9250 4125);
WIRE 16 -1 (-9250 4175)(-9250 4125);
WIRE 16 -1 (-9250 4175)(-9125 4175);
WIRE 16 -1 (-9250 4225)(-9250 4175);
WIRE 16 -1 (-9250 4225)(-9125 4225);
WIRE 16 -1 (-9250 4275)(-9250 4225);
WIRE 16 -1 (-9250 4275)(-9125 4275);
WIRE 16 -1 (-9250 4325)(-9250 4275);
WIRE 16 -1 (-9250 4325)(-9125 4325);
WIRE 16 -1 (-9250 4375)(-9250 4325);
WIRE 16 -1 (-9250 4375)(-9125 4375);
WIRE 16 -1 (-9250 4425)(-9250 4375);
WIRE 16 -1 (-9250 4425)(-9125 4425);
WIRE 16 -1 (-9250 4475)(-9250 4425);
WIRE 16 -1 (-9125 4475)(-9250 4475);
WIRE 16 -1 (-9250 4525)(-9250 4475);
WIRE 16 -1 (-9125 4525)(-9250 4525);
WIRE 16 -1 (-9250 4575)(-9250 4525);
WIRE 16 -1 (-9250 4575)(-9125 4575);
WIRE 16 -1 (-9250 4625)(-9250 4575);
WIRE 16 -1 (-9250 4625)(-9125 4625);
WIRE 16 -1 (-9250 4675)(-9250 4625);
WIRE 16 -1 (-9250 4675)(-9125 4675);
WIRE 16 -1 (-9250 4725)(-9250 4675);
WIRE 16 -1 (-9250 4725)(-9125 4725);
WIRE 16 -1 (-9250 4775)(-9250 4725);
WIRE 16 -1 (-9250 4775)(-9125 4775);
WIRE 16 -1 (-9250 4825)(-9250 4775);
WIRE 16 -1 (-9250 4825)(-9125 4825);
WIRE 16 -1 (-9250 4875)(-9250 4825);
WIRE 16 -1 (-9125 4875)(-9250 4875);
WIRE 16 -1 (-9250 4925)(-9250 4875);
WIRE 16 -1 (-9125 4925)(-9250 4925);
WIRE 16 -1 (-9250 4975)(-9250 4925);
WIRE 16 -1 (-9250 4975)(-9125 4975);
WIRE 16 -1 (-9250 5025)(-9250 4975);
WIRE 16 -1 (-9250 5025)(-9125 5025);
WIRE 16 -1 (-9250 5075)(-9250 5025);
WIRE 16 -1 (-9250 5075)(-9125 5075);
WIRE 16 -1 (-9250 5125)(-9250 5075);
WIRE 16 -1 (-9250 5125)(-9125 5125);
WIRE 16 -1 (-9250 5175)(-9250 5125);
WIRE 16 -1 (-9250 5175)(-9125 5175);
WIRE 16 -1 (-9250 5225)(-9250 5175);
WIRE 16 -1 (-9250 5225)(-9125 5225);
WIRE 16 -1 (-9250 5275)(-9250 5225);
WIRE 16 -1 (-9125 5275)(-9250 5275);
WIRE 16 -1 (-9250 5325)(-9250 5275);
WIRE 16 -1 (-9125 5325)(-9250 5325);
WIRE 16 -1 (-9250 5375)(-9250 5325);
WIRE 16 -1 (-9250 5375)(-9125 5375);
WIRE 16 -1 (-9250 5425)(-9250 5375);
WIRE 16 -1 (-9250 5425)(-9125 5425);
WIRE 16 -1 (-9250 5475)(-9250 5425);
WIRE 16 -1 (-9250 5475)(-9125 5475);
WIRE 16 -1 (-9250 5525)(-9250 5475);
WIRE 16 -1 (-9250 5525)(-9125 5525);
WIRE 16 -1 (-9250 5575)(-9250 5525);
WIRE 16 -1 (-9250 5575)(-9125 5575);
WIRE 16 -1 (-9250 5625)(-9250 5575);
WIRE 16 -1 (-9250 5625)(-9125 5625);
WIRE 16 -1 (-9250 5675)(-9250 5625);
WIRE 16 -1 (-9125 5675)(-9250 5675);
WIRE 16 -1 (-9250 5725)(-9250 5675);
WIRE 16 -1 (-9125 5725)(-9250 5725);
WIRE 16 -1 (-9250 5775)(-9250 5725);
WIRE 16 -1 (-9250 5775)(-9125 5775);
WIRE 16 -1 (-9250 5825)(-9250 5775);
WIRE 16 -1 (-9250 5825)(-9125 5825);
WIRE 16 -1 (-9250 5875)(-9250 5825);
WIRE 16 -1 (-9250 5875)(-9125 5875);
WIRE 16 -1 (-9250 5925)(-9250 5875);
WIRE 16 -1 (-9250 5925)(-9125 5925);
WIRE 16 -1 (-9250 5975)(-9250 5925);
WIRE 16 -1 (-9250 5975)(-9125 5975);
WIRE 16 -1 (-9250 6025)(-9250 5975);
WIRE 16 -1 (-9250 6025)(-9125 6025);
WIRE 16 -1 (-9250 6075)(-9250 6025);
WIRE 16 -1 (-9125 6075)(-9250 6075);
WIRE 16 -1 (-9250 6125)(-9250 6075);
WIRE 16 -1 (-9250 6175)(-9250 6125);
WIRE 16 -1 (-9125 6125)(-9250 6125);
WIRE 16 -1 (-9250 6175)(-9125 6175);
WIRE 16 -1 (-9250 6225)(-9250 6175);
WIRE 16 -1 (-9250 6225)(-9125 6225);
WIRE 16 -1 (-9250 6275)(-9250 6225);
WIRE 16 -1 (-9250 6275)(-9125 6275);
WIRE 16 -1 (-9250 6325)(-9250 6275);
WIRE 16 -1 (-9250 6325)(-9125 6325);
WIRE 16 -1 (-9250 6375)(-9250 6325);
WIRE 16 -1 (-9250 6375)(-9125 6375);
WIRE 16 -1 (-7900 525)(-7900 475);
WIRE 16 -1 (-7900 575)(-7900 525);
WIRE 16 -1 (-7900 525)(-8025 525);
WIRE 16 -1 (-7900 475)(-7900 450);
WIRE 16 -1 (-7900 475)(-8025 475);
WIRE 16 -1 (-7900 625)(-7900 575);
WIRE 16 -1 (-7900 575)(-8025 575);
WIRE 16 -1 (-7900 675)(-7900 625);
WIRE 16 -1 (-7900 625)(-8025 625);
WIRE 16 -1 (-7900 725)(-7900 675);
WIRE 16 -1 (-7900 675)(-8025 675);
WIRE 16 -1 (-8025 725)(-7900 725);
WIRE 16 -1 (-7900 775)(-7900 725);
WIRE 16 -1 (-8025 775)(-7900 775);
WIRE 16 -1 (-7900 825)(-7900 775);
WIRE 16 -1 (-7900 875)(-7900 825);
WIRE 16 -1 (-7900 825)(-8025 825);
WIRE 16 -1 (-7900 925)(-7900 875);
WIRE 16 -1 (-7900 875)(-8025 875);
WIRE 16 -1 (-7900 975)(-7900 925);
WIRE 16 -1 (-7900 925)(-8025 925);
WIRE 16 -1 (-7900 1025)(-7900 975);
WIRE 16 -1 (-7900 975)(-8025 975);
WIRE 16 -1 (-7900 1075)(-7900 1025);
WIRE 16 -1 (-7900 1025)(-8025 1025);
WIRE 16 -1 (-7900 1125)(-7900 1075);
WIRE 16 -1 (-7900 1075)(-8025 1075);
WIRE 16 -1 (-8025 1125)(-7900 1125);
WIRE 16 -1 (-7900 1175)(-7900 1125);
WIRE 16 -1 (-8025 1175)(-7900 1175);
WIRE 16 -1 (-7900 1225)(-7900 1175);
WIRE 16 -1 (-7900 1275)(-7900 1225);
WIRE 16 -1 (-7900 1225)(-8025 1225);
WIRE 16 -1 (-7900 1325)(-7900 1275);
WIRE 16 -1 (-7900 1275)(-8025 1275);
WIRE 16 -1 (-7900 1375)(-7900 1325);
WIRE 16 -1 (-7900 1325)(-8025 1325);
WIRE 16 -1 (-7900 1425)(-7900 1375);
WIRE 16 -1 (-7900 1375)(-8025 1375);
WIRE 16 -1 (-7900 1475)(-7900 1425);
WIRE 16 -1 (-7900 1425)(-8025 1425);
WIRE 16 -1 (-7900 1525)(-7900 1475);
WIRE 16 -1 (-7900 1475)(-8025 1475);
WIRE 16 -1 (-8025 1525)(-7900 1525);
WIRE 16 -1 (-7900 1575)(-7900 1525);
WIRE 16 -1 (-7900 1625)(-7900 1575);
WIRE 16 -1 (-8025 1575)(-7900 1575);
WIRE 16 -1 (-7900 1675)(-7900 1625);
WIRE 16 -1 (-7900 1625)(-8025 1625);
WIRE 16 -1 (-7900 1725)(-7900 1675);
WIRE 16 -1 (-7900 1675)(-8025 1675);
WIRE 16 -1 (-7900 1775)(-7900 1725);
WIRE 16 -1 (-7900 1725)(-8025 1725);
WIRE 16 -1 (-7900 1825)(-7900 1775);
WIRE 16 -1 (-7900 1775)(-8025 1775);
WIRE 16 -1 (-7900 1875)(-7900 1825);
WIRE 16 -1 (-7900 1825)(-8025 1825);
WIRE 16 -1 (-7900 1925)(-7900 1875);
WIRE 16 -1 (-7900 1875)(-8025 1875);
WIRE 16 -1 (-8025 1925)(-7900 1925);
WIRE 16 -1 (-7900 1975)(-7900 1925);
WIRE 16 -1 (-8025 1975)(-7900 1975);
WIRE 16 -1 (-7900 2025)(-7900 1975);
WIRE 16 -1 (-7900 2075)(-7900 2025);
WIRE 16 -1 (-7900 2025)(-8025 2025);
WIRE 16 -1 (-7900 2125)(-7900 2075);
WIRE 16 -1 (-7900 2075)(-8025 2075);
WIRE 16 -1 (-7900 2175)(-7900 2125);
WIRE 16 -1 (-7900 2125)(-8025 2125);
WIRE 16 -1 (-7900 2225)(-7900 2175);
WIRE 16 -1 (-7900 2175)(-8025 2175);
WIRE 16 -1 (-7900 2275)(-7900 2225);
WIRE 16 -1 (-7900 2225)(-8025 2225);
WIRE 16 -1 (-7900 2325)(-7900 2275);
WIRE 16 -1 (-7900 2275)(-8025 2275);
WIRE 16 -1 (-8025 2325)(-7900 2325);
WIRE 16 -1 (-7900 2375)(-7900 2325);
WIRE 16 -1 (-8025 2375)(-7900 2375);
WIRE 16 -1 (-7900 2425)(-7900 2375);
WIRE 16 -1 (-7900 2475)(-7900 2425);
WIRE 16 -1 (-7900 2425)(-8025 2425);
WIRE 16 -1 (-7900 2525)(-7900 2475);
WIRE 16 -1 (-7900 2475)(-8025 2475);
WIRE 16 -1 (-7900 2575)(-7900 2525);
WIRE 16 -1 (-7900 2525)(-8025 2525);
WIRE 16 -1 (-7900 2625)(-7900 2575);
WIRE 16 -1 (-7900 2575)(-8025 2575);
WIRE 16 -1 (-7900 2675)(-7900 2625);
WIRE 16 -1 (-7900 2625)(-8025 2625);
WIRE 16 -1 (-7900 2725)(-7900 2675);
WIRE 16 -1 (-7900 2675)(-8025 2675);
WIRE 16 -1 (-8025 2725)(-7900 2725);
WIRE 16 -1 (-7900 2775)(-7900 2725);
WIRE 16 -1 (-8025 2775)(-7900 2775);
WIRE 16 -1 (-7900 2825)(-7900 2775);
WIRE 16 -1 (-7900 2875)(-7900 2825);
WIRE 16 -1 (-7900 2825)(-8025 2825);
WIRE 16 -1 (-7900 2925)(-7900 2875);
WIRE 16 -1 (-7900 2875)(-8025 2875);
WIRE 16 -1 (-7900 2975)(-7900 2925);
WIRE 16 -1 (-7900 2925)(-8025 2925);
WIRE 16 -1 (-7900 3025)(-7900 2975);
WIRE 16 -1 (-7900 2975)(-8025 2975);
WIRE 16 -1 (-7900 3075)(-7900 3025);
WIRE 16 -1 (-7900 3025)(-8025 3025);
WIRE 16 -1 (-7900 3125)(-7900 3075);
WIRE 16 -1 (-7900 3075)(-8025 3075);
WIRE 16 -1 (-8025 3125)(-7900 3125);
WIRE 16 -1 (-7900 3175)(-7900 3125);
WIRE 16 -1 (-8025 3175)(-7900 3175);
WIRE 16 -1 (-7900 3225)(-7900 3175);
WIRE 16 -1 (-7900 3275)(-7900 3225);
WIRE 16 -1 (-7900 3225)(-8025 3225);
WIRE 16 -1 (-7900 3325)(-7900 3275);
WIRE 16 -1 (-7900 3275)(-8025 3275);
WIRE 16 -1 (-7900 3375)(-7900 3325);
WIRE 16 -1 (-7900 3325)(-8025 3325);
WIRE 16 -1 (-7900 3425)(-7900 3375);
WIRE 16 -1 (-7900 3375)(-8025 3375);
WIRE 16 -1 (-7900 3475)(-7900 3425);
WIRE 16 -1 (-7900 3425)(-8025 3425);
WIRE 16 -1 (-7900 3525)(-7900 3475);
WIRE 16 -1 (-7900 3475)(-8025 3475);
WIRE 16 -1 (-8025 3525)(-7900 3525);
WIRE 16 -1 (-7900 3575)(-7900 3525);
WIRE 16 -1 (-8025 3575)(-7900 3575);
WIRE 16 -1 (-7900 3625)(-7900 3575);
WIRE 16 -1 (-7900 3675)(-7900 3625);
WIRE 16 -1 (-7900 3625)(-8025 3625);
WIRE 16 -1 (-7900 3725)(-7900 3675);
WIRE 16 -1 (-7900 3675)(-8025 3675);
WIRE 16 -1 (-7900 3775)(-7900 3725);
WIRE 16 -1 (-7900 3725)(-8025 3725);
WIRE 16 -1 (-7900 3825)(-7900 3775);
WIRE 16 -1 (-7900 3775)(-8025 3775);
WIRE 16 -1 (-7900 3875)(-7900 3825);
WIRE 16 -1 (-7900 3825)(-8025 3825);
WIRE 16 -1 (-7900 3925)(-7900 3875);
WIRE 16 -1 (-7900 3875)(-8025 3875);
WIRE 16 -1 (-8025 3925)(-7900 3925);
WIRE 16 -1 (-7900 3975)(-7900 3925);
WIRE 16 -1 (-8025 3975)(-7900 3975);
WIRE 16 -1 (-7900 4025)(-7900 3975);
WIRE 16 -1 (-7900 4075)(-7900 4025);
WIRE 16 -1 (-7900 4025)(-8025 4025);
WIRE 16 -1 (-7900 4125)(-7900 4075);
WIRE 16 -1 (-7900 4075)(-8025 4075);
WIRE 16 -1 (-7900 4175)(-7900 4125);
WIRE 16 -1 (-7900 4125)(-8025 4125);
WIRE 16 -1 (-7900 4225)(-7900 4175);
WIRE 16 -1 (-7900 4175)(-8025 4175);
WIRE 16 -1 (-7900 4275)(-7900 4225);
WIRE 16 -1 (-7900 4225)(-8025 4225);
WIRE 16 -1 (-7900 4325)(-7900 4275);
WIRE 16 -1 (-7900 4275)(-8025 4275);
WIRE 16 -1 (-8025 4325)(-7900 4325);
WIRE 16 -1 (-7900 4375)(-7900 4325);
WIRE 16 -1 (-8025 4375)(-7900 4375);
WIRE 16 -1 (-7900 4425)(-7900 4375);
WIRE 16 -1 (-7900 4475)(-7900 4425);
WIRE 16 -1 (-7900 4425)(-8025 4425);
WIRE 16 -1 (-7900 4525)(-7900 4475);
WIRE 16 -1 (-7900 4475)(-8025 4475);
WIRE 16 -1 (-7900 4575)(-7900 4525);
WIRE 16 -1 (-7900 4525)(-8025 4525);
WIRE 16 -1 (-7900 4625)(-7900 4575);
WIRE 16 -1 (-7900 4575)(-8025 4575);
WIRE 16 -1 (-7900 4675)(-7900 4625);
WIRE 16 -1 (-7900 4625)(-8025 4625);
WIRE 16 -1 (-7900 4725)(-7900 4675);
WIRE 16 -1 (-7900 4675)(-8025 4675);
WIRE 16 -1 (-8025 4725)(-7900 4725);
WIRE 16 -1 (-7900 4775)(-7900 4725);
WIRE 16 -1 (-8025 4775)(-7900 4775);
WIRE 16 -1 (-7900 4825)(-7900 4775);
WIRE 16 -1 (-7900 4875)(-7900 4825);
WIRE 16 -1 (-7900 4825)(-8025 4825);
WIRE 16 -1 (-7900 4925)(-7900 4875);
WIRE 16 -1 (-7900 4875)(-8025 4875);
WIRE 16 -1 (-7900 4975)(-7900 4925);
WIRE 16 -1 (-7900 4925)(-8025 4925);
WIRE 16 -1 (-7900 5025)(-7900 4975);
WIRE 16 -1 (-7900 4975)(-8025 4975);
WIRE 16 -1 (-7900 5075)(-7900 5025);
WIRE 16 -1 (-7900 5025)(-8025 5025);
WIRE 16 -1 (-7900 5125)(-7900 5075);
WIRE 16 -1 (-7900 5075)(-8025 5075);
WIRE 16 -1 (-7900 5175)(-7900 5125);
WIRE 16 -1 (-8025 5125)(-7900 5125);
WIRE 16 -1 (-8025 5175)(-7900 5175);
WIRE 16 -1 (-7900 5225)(-7900 5175);
WIRE 16 -1 (-7900 5275)(-7900 5225);
WIRE 16 -1 (-7900 5225)(-8025 5225);
WIRE 16 -1 (-7900 5325)(-7900 5275);
WIRE 16 -1 (-7900 5275)(-8025 5275);
WIRE 16 -1 (-7900 5375)(-7900 5325);
WIRE 16 -1 (-7900 5325)(-8025 5325);
WIRE 16 -1 (-7900 5425)(-7900 5375);
WIRE 16 -1 (-7900 5375)(-8025 5375);
WIRE 16 -1 (-7900 5475)(-7900 5425);
WIRE 16 -1 (-7900 5425)(-8025 5425);
WIRE 16 -1 (-7900 5525)(-7900 5475);
WIRE 16 -1 (-7900 5475)(-8025 5475);
WIRE 16 -1 (-8025 5525)(-7900 5525);
WIRE 16 -1 (-7900 5575)(-7900 5525);
WIRE 16 -1 (-8025 5575)(-7900 5575);
WIRE 16 -1 (-7900 5625)(-7900 5575);
WIRE 16 -1 (-7900 5675)(-7900 5625);
WIRE 16 -1 (-7900 5625)(-8025 5625);
WIRE 16 -1 (-7900 5725)(-7900 5675);
WIRE 16 -1 (-7900 5675)(-8025 5675);
WIRE 16 -1 (-7900 5775)(-7900 5725);
WIRE 16 -1 (-7900 5725)(-8025 5725);
WIRE 16 -1 (-7900 5825)(-7900 5775);
WIRE 16 -1 (-7900 5775)(-8025 5775);
WIRE 16 -1 (-7900 5875)(-7900 5825);
WIRE 16 -1 (-7900 5825)(-8025 5825);
WIRE 16 -1 (-7900 5925)(-7900 5875);
WIRE 16 -1 (-7900 5875)(-8025 5875);
WIRE 16 -1 (-8025 5925)(-7900 5925);
WIRE 16 -1 (-7900 5975)(-7900 5925);
WIRE 16 -1 (-8025 5975)(-7900 5975);
WIRE 16 -1 (-7900 6025)(-7900 5975);
WIRE 16 -1 (-8025 6025)(-7900 6025);
WIRE 16 -1 (-7900 6075)(-7900 6025);
WIRE 16 -1 (-8025 6075)(-7900 6075);
WIRE 16 -1 (-7900 6125)(-7900 6075);
WIRE 16 -1 (-8025 6125)(-7900 6125);
WIRE 16 -1 (-7900 6175)(-7900 6125);
WIRE 16 -1 (-7900 6225)(-7900 6175);
WIRE 16 -1 (-8025 6175)(-7900 6175);
WIRE 16 -1 (-8025 6225)(-7900 6225);
WIRE 16 -1 (-7900 6275)(-7900 6225);
WIRE 16 -1 (-8025 6275)(-7900 6275);
WIRE 16 -1 (-7900 6325)(-7900 6275);
WIRE 16 -1 (-7900 6375)(-7900 6325);
WIRE 16 -1 (-7900 6325)(-8025 6325);
WIRE 16 -1 (-7900 6375)(-8025 6375);
WIRE 16 -1 (-7600 500)(-7725 500);
WIRE 16 -1 (-7725 550)(-7725 500);
WIRE 16 -1 (-7725 500)(-7725 450);
WIRE 16 -1 (-7600 550)(-7725 550);
WIRE 16 -1 (-7725 600)(-7725 550);
WIRE 16 -1 (-7600 600)(-7725 600);
WIRE 16 -1 (-7725 650)(-7725 600);
WIRE 16 -1 (-7600 650)(-7725 650);
WIRE 16 -1 (-7725 700)(-7725 650);
WIRE 16 -1 (-7600 700)(-7725 700);
WIRE 16 -1 (-7725 750)(-7725 700);
WIRE 16 -1 (-7600 750)(-7725 750);
WIRE 16 -1 (-7725 800)(-7725 750);
WIRE 16 -1 (-7600 800)(-7725 800);
WIRE 16 -1 (-7725 850)(-7725 800);
WIRE 16 -1 (-7600 850)(-7725 850);
WIRE 16 -1 (-7725 900)(-7725 850);
WIRE 16 -1 (-7725 900)(-7600 900);
WIRE 16 -1 (-7725 950)(-7725 900);
WIRE 16 -1 (-7725 950)(-7600 950);
WIRE 16 -1 (-7725 1000)(-7725 950);
WIRE 16 -1 (-7725 1050)(-7725 1000);
WIRE 16 -1 (-7725 1000)(-7600 1000);
WIRE 16 -1 (-7725 1050)(-7600 1050);
WIRE 16 -1 (-7725 1100)(-7725 1050);
WIRE 16 -1 (-7725 1100)(-7600 1100);
WIRE 16 -1 (-7725 1150)(-7725 1100);
WIRE 16 -1 (-7725 1150)(-7600 1150);
WIRE 16 -1 (-7725 1200)(-7725 1150);
WIRE 16 -1 (-7600 1200)(-7725 1200);
WIRE 16 -1 (-7725 1250)(-7725 1200);
WIRE 16 -1 (-7600 1250)(-7725 1250);
WIRE 16 -1 (-7725 1300)(-7725 1250);
WIRE 16 -1 (-7725 1300)(-7600 1300);
WIRE 16 -1 (-7725 1350)(-7725 1300);
WIRE 16 -1 (-7725 1350)(-7600 1350);
WIRE 16 -1 (-7725 1400)(-7725 1350);
WIRE 16 -1 (-7725 1400)(-7600 1400);
WIRE 16 -1 (-7725 1450)(-7725 1400);
WIRE 16 -1 (-7725 1450)(-7600 1450);
WIRE 16 -1 (-7725 1500)(-7725 1450);
WIRE 16 -1 (-7725 1500)(-7600 1500);
WIRE 16 -1 (-7725 1550)(-7725 1500);
WIRE 16 -1 (-7725 1550)(-7600 1550);
WIRE 16 -1 (-7725 1600)(-7725 1550);
WIRE 16 -1 (-7600 1600)(-7725 1600);
WIRE 16 -1 (-7725 1650)(-7725 1600);
WIRE 16 -1 (-7600 1650)(-7725 1650);
WIRE 16 -1 (-7725 1700)(-7725 1650);
WIRE 16 -1 (-7725 1700)(-7600 1700);
WIRE 16 -1 (-7725 1750)(-7725 1700);
WIRE 16 -1 (-7725 1750)(-7600 1750);
WIRE 16 -1 (-7725 1800)(-7725 1750);
WIRE 16 -1 (-7725 1800)(-7600 1800);
WIRE 16 -1 (-7725 1850)(-7725 1800);
WIRE 16 -1 (-7725 1850)(-7600 1850);
WIRE 16 -1 (-7725 1900)(-7725 1850);
WIRE 16 -1 (-7725 1900)(-7600 1900);
WIRE 16 -1 (-7725 1950)(-7725 1900);
WIRE 16 -1 (-7725 1950)(-7600 1950);
WIRE 16 -1 (-7725 2000)(-7725 1950);
WIRE 16 -1 (-7725 2050)(-7725 2000);
WIRE 16 -1 (-7600 2000)(-7725 2000);
WIRE 16 -1 (-7600 2050)(-7725 2050);
WIRE 16 -1 (-7725 2100)(-7725 2050);
WIRE 16 -1 (-7725 2100)(-7600 2100);
WIRE 16 -1 (-7725 2150)(-7725 2100);
WIRE 16 -1 (-7725 2150)(-7600 2150);
WIRE 16 -1 (-7725 2200)(-7725 2150);
WIRE 16 -1 (-7725 2200)(-7600 2200);
WIRE 16 -1 (-7725 2250)(-7725 2200);
WIRE 16 -1 (-7725 2250)(-7600 2250);
WIRE 16 -1 (-7725 2300)(-7725 2250);
WIRE 16 -1 (-7725 2300)(-7600 2300);
WIRE 16 -1 (-7725 2350)(-7725 2300);
WIRE 16 -1 (-7725 2350)(-7600 2350);
WIRE 16 -1 (-7725 2400)(-7725 2350);
WIRE 16 -1 (-7600 2400)(-7725 2400);
WIRE 16 -1 (-7725 2450)(-7725 2400);
WIRE 16 -1 (-7600 2450)(-7725 2450);
WIRE 16 -1 (-7725 2500)(-7725 2450);
WIRE 16 -1 (-7725 2500)(-7600 2500);
WIRE 16 -1 (-7725 2550)(-7725 2500);
WIRE 16 -1 (-7725 2550)(-7600 2550);
WIRE 16 -1 (-7725 2600)(-7725 2550);
WIRE 16 -1 (-7725 2600)(-7600 2600);
WIRE 16 -1 (-7725 2650)(-7725 2600);
WIRE 16 -1 (-7725 2650)(-7600 2650);
WIRE 16 -1 (-7725 2700)(-7725 2650);
WIRE 16 -1 (-7725 2700)(-7600 2700);
WIRE 16 -1 (-7725 2750)(-7725 2700);
WIRE 16 -1 (-7725 2750)(-7600 2750);
WIRE 16 -1 (-7725 2800)(-7725 2750);
WIRE 16 -1 (-7600 2800)(-7725 2800);
WIRE 16 -1 (-7725 2850)(-7725 2800);
WIRE 16 -1 (-7600 2850)(-7725 2850);
WIRE 16 -1 (-7725 2900)(-7725 2850);
WIRE 16 -1 (-7725 2900)(-7600 2900);
WIRE 16 -1 (-7725 2950)(-7725 2900);
WIRE 16 -1 (-7725 2950)(-7600 2950);
WIRE 16 -1 (-7725 3000)(-7725 2950);
WIRE 16 -1 (-7725 3000)(-7600 3000);
WIRE 16 -1 (-7725 3050)(-7725 3000);
WIRE 16 -1 (-7725 3100)(-7725 3050);
WIRE 16 -1 (-7725 3050)(-7600 3050);
WIRE 16 -1 (-7725 3100)(-7600 3100);
WIRE 16 -1 (-7725 3150)(-7725 3100);
WIRE 16 -1 (-7725 3150)(-7600 3150);
WIRE 16 -1 (-7725 3200)(-7725 3150);
WIRE 16 -1 (-7600 3200)(-7725 3200);
WIRE 16 -1 (-7725 3250)(-7725 3200);
WIRE 16 -1 (-7600 3250)(-7725 3250);
WIRE 16 -1 (-7725 3300)(-7725 3250);
WIRE 16 -1 (-7725 3300)(-7600 3300);
WIRE 16 -1 (-7725 3350)(-7725 3300);
WIRE 16 -1 (-7725 3350)(-7600 3350);
WIRE 16 -1 (-7725 3400)(-7725 3350);
WIRE 16 -1 (-7725 3400)(-7600 3400);
WIRE 16 -1 (-7725 3450)(-7725 3400);
WIRE 16 -1 (-7725 3450)(-7600 3450);
WIRE 16 -1 (-7725 3500)(-7725 3450);
WIRE 16 -1 (-7725 3500)(-7600 3500);
WIRE 16 -1 (-7725 3550)(-7725 3500);
WIRE 16 -1 (-7725 3550)(-7600 3550);
WIRE 16 -1 (-7725 3600)(-7725 3550);
WIRE 16 -1 (-7600 3600)(-7725 3600);
WIRE 16 -1 (-7725 3650)(-7725 3600);
WIRE 16 -1 (-7600 3650)(-7725 3650);
WIRE 16 -1 (-7725 3700)(-7725 3650);
WIRE 16 -1 (-7725 3700)(-7600 3700);
WIRE 16 -1 (-7725 3750)(-7725 3700);
WIRE 16 -1 (-7725 3750)(-7600 3750);
WIRE 16 -1 (-7725 3800)(-7725 3750);
WIRE 16 -1 (-7725 3800)(-7600 3800);
WIRE 16 -1 (-7725 3850)(-7725 3800);
WIRE 16 -1 (-7725 3850)(-7600 3850);
WIRE 16 -1 (-7725 3900)(-7725 3850);
WIRE 16 -1 (-7725 3900)(-7600 3900);
WIRE 16 -1 (-7725 3950)(-7725 3900);
WIRE 16 -1 (-7725 3950)(-7600 3950);
WIRE 16 -1 (-7725 4000)(-7725 3950);
WIRE 16 -1 (-7600 4000)(-7725 4000);
WIRE 16 -1 (-7725 4050)(-7725 4000);
WIRE 16 -1 (-7725 4100)(-7725 4050);
WIRE 16 -1 (-7600 4050)(-7725 4050);
WIRE 16 -1 (-7725 4100)(-7600 4100);
WIRE 16 -1 (-7725 4150)(-7725 4100);
WIRE 16 -1 (-7725 4150)(-7600 4150);
WIRE 16 -1 (-7725 4200)(-7725 4150);
WIRE 16 -1 (-7725 4200)(-7600 4200);
WIRE 16 -1 (-7725 4250)(-7725 4200);
WIRE 16 -1 (-7725 4250)(-7600 4250);
WIRE 16 -1 (-7725 4300)(-7725 4250);
WIRE 16 -1 (-7725 4300)(-7600 4300);
WIRE 16 -1 (-7725 4350)(-7725 4300);
WIRE 16 -1 (-7725 4350)(-7600 4350);
WIRE 16 -1 (-7725 4400)(-7725 4350);
WIRE 16 -1 (-7600 4400)(-7725 4400);
WIRE 16 -1 (-7725 4450)(-7725 4400);
WIRE 16 -1 (-7600 4450)(-7725 4450);
WIRE 16 -1 (-7725 4500)(-7725 4450);
WIRE 16 -1 (-7725 4500)(-7600 4500);
WIRE 16 -1 (-7725 4550)(-7725 4500);
WIRE 16 -1 (-7725 4550)(-7600 4550);
WIRE 16 -1 (-7725 4600)(-7725 4550);
WIRE 16 -1 (-7725 4600)(-7600 4600);
WIRE 16 -1 (-7725 4650)(-7725 4600);
WIRE 16 -1 (-7725 4650)(-7600 4650);
WIRE 16 -1 (-7725 4700)(-7725 4650);
WIRE 16 -1 (-7725 4700)(-7600 4700);
WIRE 16 -1 (-7725 4750)(-7725 4700);
WIRE 16 -1 (-7725 4750)(-7600 4750);
WIRE 16 -1 (-7725 4800)(-7725 4750);
WIRE 16 -1 (-7600 4800)(-7725 4800);
WIRE 16 -1 (-7725 4850)(-7725 4800);
WIRE 16 -1 (-7600 4850)(-7725 4850);
WIRE 16 -1 (-7725 4900)(-7725 4850);
WIRE 16 -1 (-7725 4900)(-7600 4900);
WIRE 16 -1 (-7725 4950)(-7725 4900);
WIRE 16 -1 (-7725 4950)(-7600 4950);
WIRE 16 -1 (-7725 5000)(-7725 4950);
WIRE 16 -1 (-7725 5000)(-7600 5000);
WIRE 16 -1 (-7725 5050)(-7725 5000);
WIRE 16 -1 (-7725 5050)(-7600 5050);
WIRE 16 -1 (-7725 5100)(-7725 5050);
WIRE 16 -1 (-7725 5150)(-7725 5100);
WIRE 16 -1 (-7725 5100)(-7600 5100);
WIRE 16 -1 (-7725 5150)(-7600 5150);
WIRE 16 -1 (-7725 5200)(-7725 5150);
WIRE 16 -1 (-7600 5200)(-7725 5200);
WIRE 16 -1 (-7725 5250)(-7725 5200);
WIRE 16 -1 (-7600 5250)(-7725 5250);
WIRE 16 -1 (-7725 5300)(-7725 5250);
WIRE 16 -1 (-7725 5300)(-7600 5300);
WIRE 16 -1 (-7725 5350)(-7725 5300);
WIRE 16 -1 (-7725 5350)(-7600 5350);
WIRE 16 -1 (-7725 5400)(-7725 5350);
WIRE 16 -1 (-7725 5400)(-7600 5400);
WIRE 16 -1 (-7725 5450)(-7725 5400);
WIRE 16 -1 (-7725 5450)(-7600 5450);
WIRE 16 -1 (-7725 5500)(-7725 5450);
WIRE 16 -1 (-7725 5500)(-7600 5500);
WIRE 16 -1 (-7725 5550)(-7725 5500);
WIRE 16 -1 (-7725 5550)(-7600 5550);
WIRE 16 -1 (-7725 5600)(-7725 5550);
WIRE 16 -1 (-7600 5600)(-7725 5600);
WIRE 16 -1 (-7725 5650)(-7725 5600);
WIRE 16 -1 (-7600 5650)(-7725 5650);
WIRE 16 -1 (-7725 5700)(-7725 5650);
WIRE 16 -1 (-7725 5700)(-7600 5700);
WIRE 16 -1 (-7725 5750)(-7725 5700);
WIRE 16 -1 (-7725 5750)(-7600 5750);
WIRE 16 -1 (-7725 5800)(-7725 5750);
WIRE 16 -1 (-7725 5800)(-7600 5800);
WIRE 16 -1 (-7725 5850)(-7725 5800);
WIRE 16 -1 (-7725 5850)(-7600 5850);
WIRE 16 -1 (-7725 5900)(-7725 5850);
WIRE 16 -1 (-7725 5900)(-7600 5900);
WIRE 16 -1 (-7725 5950)(-7725 5900);
WIRE 16 -1 (-7725 5950)(-7600 5950);
WIRE 16 -1 (-7725 6000)(-7725 5950);
WIRE 16 -1 (-7600 6000)(-7725 6000);
WIRE 16 -1 (-7725 6050)(-7725 6000);
WIRE 16 -1 (-7600 6050)(-7725 6050);
WIRE 16 -1 (-7725 6100)(-7725 6050);
WIRE 16 -1 (-7725 6150)(-7725 6100);
WIRE 16 -1 (-7725 6100)(-7600 6100);
WIRE 16 -1 (-7725 6150)(-7600 6150);
WIRE 16 -1 (-7725 6200)(-7725 6150);
WIRE 16 -1 (-7725 6200)(-7600 6200);
WIRE 16 -1 (-7725 6250)(-7725 6200);
WIRE 16 -1 (-7725 6250)(-7600 6250);
WIRE 16 -1 (-7725 6300)(-7725 6250);
WIRE 16 -1 (-7725 6300)(-7600 6300);
WIRE 16 -1 (-6375 550)(-6375 500);
WIRE 16 -1 (-6375 600)(-6375 550);
WIRE 16 -1 (-6375 550)(-6500 550);
WIRE 16 -1 (-6375 500)(-6375 475);
WIRE 16 -1 (-6375 500)(-6500 500);
WIRE 16 -1 (-6375 650)(-6375 600);
WIRE 16 -1 (-6375 600)(-6500 600);
WIRE 16 -1 (-6375 700)(-6375 650);
WIRE 16 -1 (-6375 650)(-6500 650);
WIRE 16 -1 (-6375 750)(-6375 700);
WIRE 16 -1 (-6375 700)(-6500 700);
WIRE 16 -1 (-6500 750)(-6375 750);
WIRE 16 -1 (-6375 800)(-6375 750);
WIRE 16 -1 (-6500 800)(-6375 800);
WIRE 16 -1 (-6375 850)(-6375 800);
WIRE 16 -1 (-6375 900)(-6375 850);
WIRE 16 -1 (-6375 850)(-6500 850);
WIRE 16 -1 (-6375 950)(-6375 900);
WIRE 16 -1 (-6375 900)(-6500 900);
WIRE 16 -1 (-6375 1000)(-6375 950);
WIRE 16 -1 (-6375 950)(-6500 950);
WIRE 16 -1 (-6375 1050)(-6375 1000);
WIRE 16 -1 (-6375 1000)(-6500 1000);
WIRE 16 -1 (-6375 1100)(-6375 1050);
WIRE 16 -1 (-6375 1050)(-6500 1050);
WIRE 16 -1 (-6375 1150)(-6375 1100);
WIRE 16 -1 (-6375 1100)(-6500 1100);
WIRE 16 -1 (-6500 1150)(-6375 1150);
WIRE 16 -1 (-6375 1200)(-6375 1150);
WIRE 16 -1 (-6500 1200)(-6375 1200);
WIRE 16 -1 (-6375 1250)(-6375 1200);
WIRE 16 -1 (-6375 1300)(-6375 1250);
WIRE 16 -1 (-6375 1250)(-6500 1250);
WIRE 16 -1 (-6375 1350)(-6375 1300);
WIRE 16 -1 (-6375 1300)(-6500 1300);
WIRE 16 -1 (-6375 1400)(-6375 1350);
WIRE 16 -1 (-6375 1350)(-6500 1350);
WIRE 16 -1 (-6375 1450)(-6375 1400);
WIRE 16 -1 (-6375 1400)(-6500 1400);
WIRE 16 -1 (-6375 1500)(-6375 1450);
WIRE 16 -1 (-6375 1450)(-6500 1450);
WIRE 16 -1 (-6375 1550)(-6375 1500);
WIRE 16 -1 (-6375 1500)(-6500 1500);
WIRE 16 -1 (-6375 1600)(-6375 1550);
WIRE 16 -1 (-6500 1550)(-6375 1550);
WIRE 16 -1 (-6500 1600)(-6375 1600);
WIRE 16 -1 (-6375 1650)(-6375 1600);
WIRE 16 -1 (-6375 1700)(-6375 1650);
WIRE 16 -1 (-6375 1650)(-6500 1650);
WIRE 16 -1 (-6375 1750)(-6375 1700);
WIRE 16 -1 (-6375 1700)(-6500 1700);
WIRE 16 -1 (-6375 1800)(-6375 1750);
WIRE 16 -1 (-6375 1750)(-6500 1750);
WIRE 16 -1 (-6375 1850)(-6375 1800);
WIRE 16 -1 (-6375 1800)(-6500 1800);
WIRE 16 -1 (-6375 1900)(-6375 1850);
WIRE 16 -1 (-6375 1850)(-6500 1850);
WIRE 16 -1 (-6375 1950)(-6375 1900);
WIRE 16 -1 (-6375 1900)(-6500 1900);
WIRE 16 -1 (-6500 1950)(-6375 1950);
WIRE 16 -1 (-6375 2000)(-6375 1950);
WIRE 16 -1 (-6500 2000)(-6375 2000);
WIRE 16 -1 (-6375 2050)(-6375 2000);
WIRE 16 -1 (-6375 2100)(-6375 2050);
WIRE 16 -1 (-6375 2050)(-6500 2050);
WIRE 16 -1 (-6375 2150)(-6375 2100);
WIRE 16 -1 (-6375 2100)(-6500 2100);
WIRE 16 -1 (-6375 2200)(-6375 2150);
WIRE 16 -1 (-6375 2150)(-6500 2150);
WIRE 16 -1 (-6375 2250)(-6375 2200);
WIRE 16 -1 (-6375 2200)(-6500 2200);
WIRE 16 -1 (-6375 2300)(-6375 2250);
WIRE 16 -1 (-6375 2250)(-6500 2250);
WIRE 16 -1 (-6375 2350)(-6375 2300);
WIRE 16 -1 (-6375 2300)(-6500 2300);
WIRE 16 -1 (-6500 2350)(-6375 2350);
WIRE 16 -1 (-6375 2400)(-6375 2350);
WIRE 16 -1 (-6500 2400)(-6375 2400);
WIRE 16 -1 (-6375 2450)(-6375 2400);
WIRE 16 -1 (-6375 2500)(-6375 2450);
WIRE 16 -1 (-6375 2450)(-6500 2450);
WIRE 16 -1 (-6375 2550)(-6375 2500);
WIRE 16 -1 (-6375 2500)(-6500 2500);
WIRE 16 -1 (-6375 2600)(-6375 2550);
WIRE 16 -1 (-6375 2550)(-6500 2550);
WIRE 16 -1 (-6375 2650)(-6375 2600);
WIRE 16 -1 (-6375 2600)(-6500 2600);
WIRE 16 -1 (-6375 2700)(-6375 2650);
WIRE 16 -1 (-6375 2650)(-6500 2650);
WIRE 16 -1 (-6375 2750)(-6375 2700);
WIRE 16 -1 (-6375 2700)(-6500 2700);
WIRE 16 -1 (-6500 2750)(-6375 2750);
WIRE 16 -1 (-6375 2800)(-6375 2750);
WIRE 16 -1 (-6500 2800)(-6375 2800);
WIRE 16 -1 (-6375 2850)(-6375 2800);
WIRE 16 -1 (-6375 2900)(-6375 2850);
WIRE 16 -1 (-6375 2850)(-6500 2850);
WIRE 16 -1 (-6375 2950)(-6375 2900);
WIRE 16 -1 (-6375 2900)(-6500 2900);
WIRE 16 -1 (-6375 3000)(-6375 2950);
WIRE 16 -1 (-6375 2950)(-6500 2950);
WIRE 16 -1 (-6375 3050)(-6375 3000);
WIRE 16 -1 (-6375 3000)(-6500 3000);
WIRE 16 -1 (-6375 3100)(-6375 3050);
WIRE 16 -1 (-6375 3050)(-6500 3050);
WIRE 16 -1 (-6375 3150)(-6375 3100);
WIRE 16 -1 (-6375 3100)(-6500 3100);
WIRE 16 -1 (-6500 3150)(-6375 3150);
WIRE 16 -1 (-6375 3200)(-6375 3150);
WIRE 16 -1 (-6500 3200)(-6375 3200);
WIRE 16 -1 (-6375 3250)(-6375 3200);
WIRE 16 -1 (-6375 3300)(-6375 3250);
WIRE 16 -1 (-6375 3250)(-6500 3250);
WIRE 16 -1 (-6375 3350)(-6375 3300);
WIRE 16 -1 (-6375 3300)(-6500 3300);
WIRE 16 -1 (-6375 3400)(-6375 3350);
WIRE 16 -1 (-6375 3350)(-6500 3350);
WIRE 16 -1 (-6375 3450)(-6375 3400);
WIRE 16 -1 (-6375 3400)(-6500 3400);
WIRE 16 -1 (-6375 3500)(-6375 3450);
WIRE 16 -1 (-6375 3450)(-6500 3450);
WIRE 16 -1 (-6375 3550)(-6375 3500);
WIRE 16 -1 (-6375 3500)(-6500 3500);
WIRE 16 -1 (-6500 3550)(-6375 3550);
WIRE 16 -1 (-6375 3600)(-6375 3550);
WIRE 16 -1 (-6375 3650)(-6375 3600);
WIRE 16 -1 (-6500 3600)(-6375 3600);
WIRE 16 -1 (-6375 3700)(-6375 3650);
WIRE 16 -1 (-6375 3650)(-6500 3650);
WIRE 16 -1 (-6375 3750)(-6375 3700);
WIRE 16 -1 (-6375 3700)(-6500 3700);
WIRE 16 -1 (-6375 3800)(-6375 3750);
WIRE 16 -1 (-6375 3750)(-6500 3750);
WIRE 16 -1 (-6375 3850)(-6375 3800);
WIRE 16 -1 (-6375 3800)(-6500 3800);
WIRE 16 -1 (-6375 3900)(-6375 3850);
WIRE 16 -1 (-6375 3850)(-6500 3850);
WIRE 16 -1 (-6375 3950)(-6375 3900);
WIRE 16 -1 (-6375 3900)(-6500 3900);
WIRE 16 -1 (-6500 3950)(-6375 3950);
WIRE 16 -1 (-6375 4000)(-6375 3950);
WIRE 16 -1 (-6500 4000)(-6375 4000);
WIRE 16 -1 (-6375 4050)(-6375 4000);
WIRE 16 -1 (-6375 4100)(-6375 4050);
WIRE 16 -1 (-6375 4050)(-6500 4050);
WIRE 16 -1 (-6375 4150)(-6375 4100);
WIRE 16 -1 (-6375 4100)(-6500 4100);
WIRE 16 -1 (-6375 4200)(-6375 4150);
WIRE 16 -1 (-6375 4150)(-6500 4150);
WIRE 16 -1 (-6375 4250)(-6375 4200);
WIRE 16 -1 (-6375 4200)(-6500 4200);
WIRE 16 -1 (-6375 4300)(-6375 4250);
WIRE 16 -1 (-6375 4250)(-6500 4250);
WIRE 16 -1 (-6375 4350)(-6375 4300);
WIRE 16 -1 (-6375 4300)(-6500 4300);
WIRE 16 -1 (-6500 4350)(-6375 4350);
WIRE 16 -1 (-6375 4400)(-6375 4350);
WIRE 16 -1 (-6500 4400)(-6375 4400);
WIRE 16 -1 (-6375 4450)(-6375 4400);
WIRE 16 -1 (-6375 4500)(-6375 4450);
WIRE 16 -1 (-6375 4450)(-6500 4450);
WIRE 16 -1 (-6375 4550)(-6375 4500);
WIRE 16 -1 (-6375 4500)(-6500 4500);
WIRE 16 -1 (-6375 4600)(-6375 4550);
WIRE 16 -1 (-6375 4550)(-6500 4550);
WIRE 16 -1 (-6375 4650)(-6375 4600);
WIRE 16 -1 (-6375 4600)(-6500 4600);
WIRE 16 -1 (-6375 4700)(-6375 4650);
WIRE 16 -1 (-6375 4650)(-6500 4650);
WIRE 16 -1 (-6375 4750)(-6375 4700);
WIRE 16 -1 (-6375 4700)(-6500 4700);
WIRE 16 -1 (-6500 4750)(-6375 4750);
WIRE 16 -1 (-6375 4800)(-6375 4750);
WIRE 16 -1 (-6500 4800)(-6375 4800);
WIRE 16 -1 (-6375 4850)(-6375 4800);
WIRE 16 -1 (-6375 4900)(-6375 4850);
WIRE 16 -1 (-6375 4850)(-6500 4850);
WIRE 16 -1 (-6375 4950)(-6375 4900);
WIRE 16 -1 (-6375 4900)(-6500 4900);
WIRE 16 -1 (-6375 5000)(-6375 4950);
WIRE 16 -1 (-6375 4950)(-6500 4950);
WIRE 16 -1 (-6375 5050)(-6375 5000);
WIRE 16 -1 (-6375 5000)(-6500 5000);
WIRE 16 -1 (-6375 5100)(-6375 5050);
WIRE 16 -1 (-6375 5050)(-6500 5050);
WIRE 16 -1 (-6375 5150)(-6375 5100);
WIRE 16 -1 (-6375 5100)(-6500 5100);
WIRE 16 -1 (-6375 5200)(-6375 5150);
WIRE 16 -1 (-6500 5150)(-6375 5150);
WIRE 16 -1 (-6500 5200)(-6375 5200);
WIRE 16 -1 (-6375 5250)(-6375 5200);
WIRE 16 -1 (-6375 5300)(-6375 5250);
WIRE 16 -1 (-6375 5250)(-6500 5250);
WIRE 16 -1 (-6375 5350)(-6375 5300);
WIRE 16 -1 (-6375 5300)(-6500 5300);
WIRE 16 -1 (-6375 5400)(-6375 5350);
WIRE 16 -1 (-6375 5350)(-6500 5350);
WIRE 16 -1 (-6375 5450)(-6375 5400);
WIRE 16 -1 (-6375 5400)(-6500 5400);
WIRE 16 -1 (-6375 5500)(-6375 5450);
WIRE 16 -1 (-6375 5450)(-6500 5450);
WIRE 16 -1 (-6375 5550)(-6375 5500);
WIRE 16 -1 (-6375 5500)(-6500 5500);
WIRE 16 -1 (-6500 5550)(-6375 5550);
WIRE 16 -1 (-6375 5600)(-6375 5550);
WIRE 16 -1 (-6500 5600)(-6375 5600);
WIRE 16 -1 (-6375 5650)(-6375 5600);
WIRE 16 -1 (-6375 5700)(-6375 5650);
WIRE 16 -1 (-6375 5650)(-6500 5650);
WIRE 16 -1 (-6375 5750)(-6375 5700);
WIRE 16 -1 (-6375 5700)(-6500 5700);
WIRE 16 -1 (-6375 5800)(-6375 5750);
WIRE 16 -1 (-6375 5750)(-6500 5750);
WIRE 16 -1 (-6375 5850)(-6375 5800);
WIRE 16 -1 (-6375 5800)(-6500 5800);
WIRE 16 -1 (-6375 5900)(-6375 5850);
WIRE 16 -1 (-6375 5850)(-6500 5850);
WIRE 16 -1 (-6375 5950)(-6375 5900);
WIRE 16 -1 (-6375 5900)(-6500 5900);
WIRE 16 -1 (-6500 5950)(-6375 5950);
WIRE 16 -1 (-6375 6000)(-6375 5950);
WIRE 16 -1 (-6500 6000)(-6375 6000);
WIRE 16 -1 (-6375 6050)(-6375 6000);
WIRE 16 -1 (-6500 6050)(-6375 6050);
WIRE 16 -1 (-6375 6100)(-6375 6050);
WIRE 16 -1 (-6500 6100)(-6375 6100);
WIRE 16 -1 (-6375 6150)(-6375 6100);
WIRE 16 -1 (-6375 6200)(-6375 6150);
WIRE 16 -1 (-6500 6150)(-6375 6150);
WIRE 16 -1 (-6500 6200)(-6375 6200);
WIRE 16 -1 (-6375 6250)(-6375 6200);
WIRE 16 -1 (-6500 6250)(-6375 6250);
WIRE 16 -1 (-6375 6300)(-6375 6250);
WIRE 16 -1 (-6500 6300)(-6375 6300);
WIRE 16 -1 (-6125 525)(-6250 525);
WIRE 16 -1 (-6250 575)(-6250 525);
WIRE 16 -1 (-6250 525)(-6250 475);
WIRE 16 -1 (-6125 575)(-6250 575);
WIRE 16 -1 (-6250 625)(-6250 575);
WIRE 16 -1 (-6125 625)(-6250 625);
WIRE 16 -1 (-6250 675)(-6250 625);
WIRE 16 -1 (-6125 675)(-6250 675);
WIRE 16 -1 (-6250 725)(-6250 675);
WIRE 16 -1 (-6125 725)(-6250 725);
WIRE 16 -1 (-6250 775)(-6250 725);
WIRE 16 -1 (-6125 775)(-6250 775);
WIRE 16 -1 (-6250 825)(-6250 775);
WIRE 16 -1 (-6125 825)(-6250 825);
WIRE 16 -1 (-6250 875)(-6250 825);
WIRE 16 -1 (-6125 875)(-6250 875);
WIRE 16 -1 (-6250 925)(-6250 875);
WIRE 16 -1 (-6250 925)(-6125 925);
WIRE 16 -1 (-6250 975)(-6250 925);
WIRE 16 -1 (-6250 975)(-6125 975);
WIRE 16 -1 (-6250 1025)(-6250 975);
WIRE 16 -1 (-6250 1025)(-6125 1025);
WIRE 16 -1 (-6250 1075)(-6250 1025);
WIRE 16 -1 (-6250 1075)(-6125 1075);
WIRE 16 -1 (-6250 1125)(-6250 1075);
WIRE 16 -1 (-6250 1125)(-6125 1125);
WIRE 16 -1 (-6250 1175)(-6250 1125);
WIRE 16 -1 (-6250 1175)(-6125 1175);
WIRE 16 -1 (-6250 1225)(-6250 1175);
WIRE 16 -1 (-6125 1225)(-6250 1225);
WIRE 16 -1 (-6250 1275)(-6250 1225);
WIRE 16 -1 (-6125 1275)(-6250 1275);
WIRE 16 -1 (-6250 1325)(-6250 1275);
WIRE 16 -1 (-6250 1325)(-6125 1325);
WIRE 16 -1 (-6250 1375)(-6250 1325);
WIRE 16 -1 (-6250 1375)(-6125 1375);
WIRE 16 -1 (-6250 1425)(-6250 1375);
WIRE 16 -1 (-6250 1425)(-6125 1425);
WIRE 16 -1 (-6250 1475)(-6250 1425);
WIRE 16 -1 (-6250 1475)(-6125 1475);
WIRE 16 -1 (-6250 1525)(-6250 1475);
WIRE 16 -1 (-6250 1525)(-6125 1525);
WIRE 16 -1 (-6250 1575)(-6250 1525);
WIRE 16 -1 (-6250 1575)(-6125 1575);
WIRE 16 -1 (-6250 1625)(-6250 1575);
WIRE 16 -1 (-6125 1625)(-6250 1625);
WIRE 16 -1 (-6250 1675)(-6250 1625);
WIRE 16 -1 (-6125 1675)(-6250 1675);
WIRE 16 -1 (-6250 1725)(-6250 1675);
WIRE 16 -1 (-6250 1725)(-6125 1725);
WIRE 16 -1 (-6250 1775)(-6250 1725);
WIRE 16 -1 (-6250 1775)(-6125 1775);
WIRE 16 -1 (-6250 1825)(-6250 1775);
WIRE 16 -1 (-6250 1825)(-6125 1825);
WIRE 16 -1 (-6250 1875)(-6250 1825);
WIRE 16 -1 (-6250 1875)(-6125 1875);
WIRE 16 -1 (-6250 1925)(-6250 1875);
WIRE 16 -1 (-6250 1925)(-6125 1925);
WIRE 16 -1 (-6250 1975)(-6250 1925);
WIRE 16 -1 (-6250 1975)(-6125 1975);
WIRE 16 -1 (-6250 2025)(-6250 1975);
WIRE 16 -1 (-6125 2025)(-6250 2025);
WIRE 16 -1 (-6250 2075)(-6250 2025);
WIRE 16 -1 (-6125 2075)(-6250 2075);
WIRE 16 -1 (-6250 2125)(-6250 2075);
WIRE 16 -1 (-6250 2125)(-6125 2125);
WIRE 16 -1 (-6250 2175)(-6250 2125);
WIRE 16 -1 (-6250 2175)(-6125 2175);
WIRE 16 -1 (-6250 2225)(-6250 2175);
WIRE 16 -1 (-6250 2225)(-6125 2225);
WIRE 16 -1 (-6250 2275)(-6250 2225);
WIRE 16 -1 (-6250 2275)(-6125 2275);
WIRE 16 -1 (-6250 2325)(-6250 2275);
WIRE 16 -1 (-6250 2325)(-6125 2325);
WIRE 16 -1 (-6250 2375)(-6250 2325);
WIRE 16 -1 (-6250 2375)(-6125 2375);
WIRE 16 -1 (-6250 2425)(-6250 2375);
WIRE 16 -1 (-6125 2425)(-6250 2425);
WIRE 16 -1 (-6250 2475)(-6250 2425);
WIRE 16 -1 (-6125 2475)(-6250 2475);
WIRE 16 -1 (-6250 2525)(-6250 2475);
WIRE 16 -1 (-6250 2525)(-6125 2525);
WIRE 16 -1 (-6250 2575)(-6250 2525);
WIRE 16 -1 (-6250 2575)(-6125 2575);
WIRE 16 -1 (-6250 2625)(-6250 2575);
WIRE 16 -1 (-6250 2625)(-6125 2625);
WIRE 16 -1 (-6250 2675)(-6250 2625);
WIRE 16 -1 (-6250 2675)(-6125 2675);
WIRE 16 -1 (-6250 2725)(-6250 2675);
WIRE 16 -1 (-6250 2725)(-6125 2725);
WIRE 16 -1 (-6250 2775)(-6250 2725);
WIRE 16 -1 (-6250 2775)(-6125 2775);
WIRE 16 -1 (-6250 2825)(-6250 2775);
WIRE 16 -1 (-6125 2825)(-6250 2825);
WIRE 16 -1 (-6250 2875)(-6250 2825);
WIRE 16 -1 (-6125 2875)(-6250 2875);
WIRE 16 -1 (-6250 2925)(-6250 2875);
WIRE 16 -1 (-6250 2925)(-6125 2925);
WIRE 16 -1 (-6250 2975)(-6250 2925);
WIRE 16 -1 (-6250 2975)(-6125 2975);
WIRE 16 -1 (-6250 3025)(-6250 2975);
WIRE 16 -1 (-6250 3025)(-6125 3025);
WIRE 16 -1 (-6250 3075)(-6250 3025);
WIRE 16 -1 (-6250 3075)(-6125 3075);
WIRE 16 -1 (-6250 3125)(-6250 3075);
WIRE 16 -1 (-6250 3125)(-6125 3125);
WIRE 16 -1 (-6250 3175)(-6250 3125);
WIRE 16 -1 (-6250 3175)(-6125 3175);
WIRE 16 -1 (-6250 3225)(-6250 3175);
WIRE 16 -1 (-6125 3225)(-6250 3225);
WIRE 16 -1 (-6250 3275)(-6250 3225);
WIRE 16 -1 (-6125 3275)(-6250 3275);
WIRE 16 -1 (-6250 3325)(-6250 3275);
WIRE 16 -1 (-6250 3325)(-6125 3325);
WIRE 16 -1 (-6250 3375)(-6250 3325);
WIRE 16 -1 (-6250 3375)(-6125 3375);
WIRE 16 -1 (-6250 3425)(-6250 3375);
WIRE 16 -1 (-6250 3425)(-6125 3425);
WIRE 16 -1 (-6250 3475)(-6250 3425);
WIRE 16 -1 (-6250 3475)(-6125 3475);
WIRE 16 -1 (-6250 3525)(-6250 3475);
WIRE 16 -1 (-6250 3525)(-6125 3525);
WIRE 16 -1 (-6250 3575)(-6250 3525);
WIRE 16 -1 (-6250 3575)(-6125 3575);
WIRE 16 -1 (-6250 3625)(-6250 3575);
WIRE 16 -1 (-6125 3625)(-6250 3625);
WIRE 16 -1 (-6250 3675)(-6250 3625);
WIRE 16 -1 (-6125 3675)(-6250 3675);
WIRE 16 -1 (-6250 3725)(-6250 3675);
WIRE 16 -1 (-6250 3725)(-6125 3725);
WIRE 16 -1 (-6250 3775)(-6250 3725);
WIRE 16 -1 (-6250 3775)(-6125 3775);
WIRE 16 -1 (-6250 3825)(-6250 3775);
WIRE 16 -1 (-6250 3825)(-6125 3825);
WIRE 16 -1 (-6250 3875)(-6250 3825);
WIRE 16 -1 (-6250 3875)(-6125 3875);
WIRE 16 -1 (-6250 3925)(-6250 3875);
WIRE 16 -1 (-6250 3925)(-6125 3925);
WIRE 16 -1 (-6250 3975)(-6250 3925);
WIRE 16 -1 (-6250 3975)(-6125 3975);
WIRE 16 -1 (-6250 4025)(-6250 3975);
WIRE 16 -1 (-6125 4025)(-6250 4025);
WIRE 16 -1 (-6250 4075)(-6250 4025);
WIRE 16 -1 (-6250 4125)(-6250 4075);
WIRE 16 -1 (-6125 4075)(-6250 4075);
WIRE 16 -1 (-6250 4125)(-6125 4125);
WIRE 16 -1 (-6250 4175)(-6250 4125);
WIRE 16 -1 (-6250 4175)(-6125 4175);
WIRE 16 -1 (-6250 4225)(-6250 4175);
WIRE 16 -1 (-6250 4225)(-6125 4225);
WIRE 16 -1 (-6250 4275)(-6250 4225);
WIRE 16 -1 (-6250 4275)(-6125 4275);
WIRE 16 -1 (-6250 4325)(-6250 4275);
WIRE 16 -1 (-6250 4325)(-6125 4325);
WIRE 16 -1 (-6250 4375)(-6250 4325);
WIRE 16 -1 (-6250 4375)(-6125 4375);
WIRE 16 -1 (-6250 4425)(-6250 4375);
WIRE 16 -1 (-6125 4425)(-6250 4425);
WIRE 16 -1 (-6250 4475)(-6250 4425);
WIRE 16 -1 (-6125 4475)(-6250 4475);
WIRE 16 -1 (-6250 4525)(-6250 4475);
WIRE 16 -1 (-6250 4525)(-6125 4525);
WIRE 16 -1 (-6250 4575)(-6250 4525);
WIRE 16 -1 (-6250 4575)(-6125 4575);
WIRE 16 -1 (-6250 4625)(-6250 4575);
WIRE 16 -1 (-6250 4625)(-6125 4625);
WIRE 16 -1 (-6250 4675)(-6250 4625);
WIRE 16 -1 (-6250 4675)(-6125 4675);
WIRE 16 -1 (-6250 4725)(-6250 4675);
WIRE 16 -1 (-6250 4725)(-6125 4725);
WIRE 16 -1 (-6250 4775)(-6250 4725);
WIRE 16 -1 (-6250 4775)(-6125 4775);
WIRE 16 -1 (-6250 4825)(-6250 4775);
WIRE 16 -1 (-6125 4825)(-6250 4825);
WIRE 16 -1 (-6250 4875)(-6250 4825);
WIRE 16 -1 (-6125 4875)(-6250 4875);
WIRE 16 -1 (-6250 4925)(-6250 4875);
WIRE 16 -1 (-6250 4925)(-6125 4925);
WIRE 16 -1 (-6250 4975)(-6250 4925);
WIRE 16 -1 (-6250 4975)(-6125 4975);
WIRE 16 -1 (-6250 5025)(-6250 4975);
WIRE 16 -1 (-6250 5025)(-6125 5025);
WIRE 16 -1 (-6250 5075)(-6250 5025);
WIRE 16 -1 (-6250 5075)(-6125 5075);
WIRE 16 -1 (-6250 5125)(-6250 5075);
WIRE 16 -1 (-6250 5125)(-6125 5125);
WIRE 16 -1 (-6250 5175)(-6250 5125);
WIRE 16 -1 (-6250 5175)(-6125 5175);
WIRE 16 -1 (-6250 5225)(-6250 5175);
WIRE 16 -1 (-6125 5225)(-6250 5225);
WIRE 16 -1 (-6250 5275)(-6250 5225);
WIRE 16 -1 (-6125 5275)(-6250 5275);
WIRE 16 -1 (-6250 5325)(-6250 5275);
WIRE 16 -1 (-6250 5325)(-6125 5325);
WIRE 16 -1 (-6250 5375)(-6250 5325);
WIRE 16 -1 (-6250 5375)(-6125 5375);
WIRE 16 -1 (-6250 5425)(-6250 5375);
WIRE 16 -1 (-6250 5425)(-6125 5425);
WIRE 16 -1 (-6250 5475)(-6250 5425);
WIRE 16 -1 (-6250 5475)(-6125 5475);
WIRE 16 -1 (-6250 5525)(-6250 5475);
WIRE 16 -1 (-6250 5525)(-6125 5525);
WIRE 16 -1 (-6250 5575)(-6250 5525);
WIRE 16 -1 (-6250 5575)(-6125 5575);
WIRE 16 -1 (-6250 5625)(-6250 5575);
WIRE 16 -1 (-6125 5625)(-6250 5625);
WIRE 16 -1 (-6250 5675)(-6250 5625);
WIRE 16 -1 (-6125 5675)(-6250 5675);
WIRE 16 -1 (-6250 5725)(-6250 5675);
WIRE 16 -1 (-6250 5725)(-6125 5725);
WIRE 16 -1 (-6250 5775)(-6250 5725);
WIRE 16 -1 (-6250 5775)(-6125 5775);
WIRE 16 -1 (-6250 5825)(-6250 5775);
WIRE 16 -1 (-6250 5825)(-6125 5825);
WIRE 16 -1 (-6250 5875)(-6250 5825);
WIRE 16 -1 (-6250 5875)(-6125 5875);
WIRE 16 -1 (-6250 5925)(-6250 5875);
WIRE 16 -1 (-6250 5925)(-6125 5925);
WIRE 16 -1 (-6250 5975)(-6250 5925);
WIRE 16 -1 (-6250 5975)(-6125 5975);
WIRE 16 -1 (-6250 6025)(-6250 5975);
WIRE 16 -1 (-6125 6025)(-6250 6025);
WIRE 16 -1 (-6250 6075)(-6250 6025);
WIRE 16 -1 (-6125 6075)(-6250 6075);
WIRE 16 -1 (-6250 6125)(-6250 6075);
WIRE 16 -1 (-6250 6125)(-6125 6125);
WIRE 16 -1 (-6250 6175)(-6250 6125);
WIRE 16 -1 (-6250 6175)(-6125 6175);
WIRE 16 -1 (-6250 6225)(-6250 6175);
WIRE 16 -1 (-6250 6225)(-6125 6225);
WIRE 16 -1 (-6250 6275)(-6250 6225);
WIRE 16 -1 (-6250 6275)(-6125 6275);
WIRE 16 -1 (-6250 6325)(-6250 6275);
WIRE 16 -1 (-6250 6325)(-6125 6325);
WIRE 16 -1 (-4900 625)(-4900 575);
WIRE 16 -1 (-4900 675)(-4900 625);
WIRE 16 -1 (-4900 625)(-5025 625);
WIRE 16 -1 (-4900 575)(-4900 550);
WIRE 16 -1 (-4900 575)(-5025 575);
WIRE 16 -1 (-4900 725)(-4900 675);
WIRE 16 -1 (-4900 675)(-5025 675);
WIRE 16 -1 (-4900 775)(-4900 725);
WIRE 16 -1 (-4900 725)(-5025 725);
WIRE 16 -1 (-4900 825)(-4900 775);
WIRE 16 -1 (-4900 775)(-5025 775);
WIRE 16 -1 (-5025 825)(-4900 825);
WIRE 16 -1 (-4900 875)(-4900 825);
WIRE 16 -1 (-5025 875)(-4900 875);
WIRE 16 -1 (-4900 925)(-4900 875);
WIRE 16 -1 (-4900 975)(-4900 925);
WIRE 16 -1 (-4900 925)(-5025 925);
WIRE 16 -1 (-4900 1025)(-4900 975);
WIRE 16 -1 (-4900 975)(-5025 975);
WIRE 16 -1 (-4900 1075)(-4900 1025);
WIRE 16 -1 (-4900 1025)(-5025 1025);
WIRE 16 -1 (-4900 1125)(-4900 1075);
WIRE 16 -1 (-4900 1075)(-5025 1075);
WIRE 16 -1 (-4900 1175)(-4900 1125);
WIRE 16 -1 (-4900 1125)(-5025 1125);
WIRE 16 -1 (-4900 1225)(-4900 1175);
WIRE 16 -1 (-4900 1175)(-5025 1175);
WIRE 16 -1 (-5025 1225)(-4900 1225);
WIRE 16 -1 (-4900 1275)(-4900 1225);
WIRE 16 -1 (-5025 1275)(-4900 1275);
WIRE 16 -1 (-4900 1325)(-4900 1275);
WIRE 16 -1 (-4900 1375)(-4900 1325);
WIRE 16 -1 (-4900 1325)(-5025 1325);
WIRE 16 -1 (-4900 1425)(-4900 1375);
WIRE 16 -1 (-4900 1375)(-5025 1375);
WIRE 16 -1 (-4900 1475)(-4900 1425);
WIRE 16 -1 (-4900 1425)(-5025 1425);
WIRE 16 -1 (-4900 1525)(-4900 1475);
WIRE 16 -1 (-4900 1475)(-5025 1475);
WIRE 16 -1 (-4900 1575)(-4900 1525);
WIRE 16 -1 (-4900 1525)(-5025 1525);
WIRE 16 -1 (-4900 1625)(-4900 1575);
WIRE 16 -1 (-4900 1575)(-5025 1575);
WIRE 16 -1 (-5025 1625)(-4900 1625);
WIRE 16 -1 (-4900 1675)(-4900 1625);
WIRE 16 -1 (-5025 1675)(-4900 1675);
WIRE 16 -1 (-4900 1725)(-4900 1675);
WIRE 16 -1 (-4900 1775)(-4900 1725);
WIRE 16 -1 (-4900 1725)(-5025 1725);
WIRE 16 -1 (-4900 1825)(-4900 1775);
WIRE 16 -1 (-4900 1775)(-5025 1775);
WIRE 16 -1 (-4900 1875)(-4900 1825);
WIRE 16 -1 (-4900 1825)(-5025 1825);
WIRE 16 -1 (-4900 1925)(-4900 1875);
WIRE 16 -1 (-4900 1875)(-5025 1875);
WIRE 16 -1 (-4900 1975)(-4900 1925);
WIRE 16 -1 (-4900 1925)(-5025 1925);
WIRE 16 -1 (-4900 2025)(-4900 1975);
WIRE 16 -1 (-4900 1975)(-5025 1975);
WIRE 16 -1 (-5025 2025)(-4900 2025);
WIRE 16 -1 (-4900 2075)(-4900 2025);
WIRE 16 -1 (-4900 2125)(-4900 2075);
WIRE 16 -1 (-5025 2075)(-4900 2075);
WIRE 16 -1 (-4900 2175)(-4900 2125);
WIRE 16 -1 (-4900 2125)(-5025 2125);
WIRE 16 -1 (-4900 2225)(-4900 2175);
WIRE 16 -1 (-4900 2175)(-5025 2175);
WIRE 16 -1 (-4900 2275)(-4900 2225);
WIRE 16 -1 (-4900 2225)(-5025 2225);
WIRE 16 -1 (-4900 2325)(-4900 2275);
WIRE 16 -1 (-4900 2275)(-5025 2275);
WIRE 16 -1 (-4900 2375)(-4900 2325);
WIRE 16 -1 (-4900 2325)(-5025 2325);
WIRE 16 -1 (-4900 2425)(-4900 2375);
WIRE 16 -1 (-4900 2375)(-5025 2375);
WIRE 16 -1 (-5025 2425)(-4900 2425);
WIRE 16 -1 (-4900 2475)(-4900 2425);
WIRE 16 -1 (-5025 2475)(-4900 2475);
WIRE 16 -1 (-4900 2525)(-4900 2475);
WIRE 16 -1 (-4900 2575)(-4900 2525);
WIRE 16 -1 (-4900 2525)(-5025 2525);
WIRE 16 -1 (-4900 2625)(-4900 2575);
WIRE 16 -1 (-4900 2575)(-5025 2575);
WIRE 16 -1 (-4900 2675)(-4900 2625);
WIRE 16 -1 (-4900 2625)(-5025 2625);
WIRE 16 -1 (-4900 2725)(-4900 2675);
WIRE 16 -1 (-4900 2675)(-5025 2675);
WIRE 16 -1 (-4900 2775)(-4900 2725);
WIRE 16 -1 (-4900 2725)(-5025 2725);
WIRE 16 -1 (-4900 2825)(-4900 2775);
WIRE 16 -1 (-4900 2775)(-5025 2775);
WIRE 16 -1 (-4900 2875)(-4900 2825);
WIRE 16 -1 (-5025 2825)(-4900 2825);
WIRE 16 -1 (-5025 2875)(-4900 2875);
WIRE 16 -1 (-4900 2925)(-4900 2875);
WIRE 16 -1 (-4900 2975)(-4900 2925);
WIRE 16 -1 (-4900 2925)(-5025 2925);
WIRE 16 -1 (-4900 3025)(-4900 2975);
WIRE 16 -1 (-4900 2975)(-5025 2975);
WIRE 16 -1 (-4900 3075)(-4900 3025);
WIRE 16 -1 (-4900 3025)(-5025 3025);
WIRE 16 -1 (-4900 3125)(-4900 3075);
WIRE 16 -1 (-4900 3075)(-5025 3075);
WIRE 16 -1 (-4900 3175)(-4900 3125);
WIRE 16 -1 (-4900 3125)(-5025 3125);
WIRE 16 -1 (-4900 3225)(-4900 3175);
WIRE 16 -1 (-4900 3175)(-5025 3175);
WIRE 16 -1 (-5025 3225)(-4900 3225);
WIRE 16 -1 (-4900 3275)(-4900 3225);
WIRE 16 -1 (-5025 3275)(-4900 3275);
WIRE 16 -1 (-4900 3325)(-4900 3275);
WIRE 16 -1 (-4900 3375)(-4900 3325);
WIRE 16 -1 (-4900 3325)(-5025 3325);
WIRE 16 -1 (-4900 3425)(-4900 3375);
WIRE 16 -1 (-4900 3375)(-5025 3375);
WIRE 16 -1 (-4900 3475)(-4900 3425);
WIRE 16 -1 (-4900 3425)(-5025 3425);
WIRE 16 -1 (-4900 3525)(-4900 3475);
WIRE 16 -1 (-4900 3475)(-5025 3475);
WIRE 16 -1 (-4900 3575)(-4900 3525);
WIRE 16 -1 (-4900 3525)(-5025 3525);
WIRE 16 -1 (-4900 3625)(-4900 3575);
WIRE 16 -1 (-4900 3575)(-5025 3575);
WIRE 16 -1 (-4900 3675)(-4900 3625);
WIRE 16 -1 (-5025 3625)(-4900 3625);
WIRE 16 -1 (-5025 3675)(-4900 3675);
WIRE 16 -1 (-4900 3725)(-4900 3675);
WIRE 16 -1 (-4900 3775)(-4900 3725);
WIRE 16 -1 (-4900 3725)(-5025 3725);
WIRE 16 -1 (-4900 3825)(-4900 3775);
WIRE 16 -1 (-4900 3775)(-5025 3775);
WIRE 16 -1 (-4900 3875)(-4900 3825);
WIRE 16 -1 (-4900 3825)(-5025 3825);
WIRE 16 -1 (-4900 3925)(-4900 3875);
WIRE 16 -1 (-4900 3875)(-5025 3875);
WIRE 16 -1 (-4900 3975)(-4900 3925);
WIRE 16 -1 (-4900 3925)(-5025 3925);
WIRE 16 -1 (-4900 4025)(-4900 3975);
WIRE 16 -1 (-4900 3975)(-5025 3975);
WIRE 16 -1 (-5025 4025)(-4900 4025);
WIRE 16 -1 (-4900 4075)(-4900 4025);
WIRE 16 -1 (-5025 4075)(-4900 4075);
WIRE 16 -1 (-4900 4125)(-4900 4075);
WIRE 16 -1 (-4900 4175)(-4900 4125);
WIRE 16 -1 (-4900 4125)(-5025 4125);
WIRE 16 -1 (-4900 4225)(-4900 4175);
WIRE 16 -1 (-4900 4175)(-5025 4175);
WIRE 16 -1 (-4900 4275)(-4900 4225);
WIRE 16 -1 (-4900 4225)(-5025 4225);
WIRE 16 -1 (-4900 4325)(-4900 4275);
WIRE 16 -1 (-4900 4275)(-5025 4275);
WIRE 16 -1 (-4900 4375)(-4900 4325);
WIRE 16 -1 (-4900 4325)(-5025 4325);
WIRE 16 -1 (-4900 4425)(-4900 4375);
WIRE 16 -1 (-4900 4375)(-5025 4375);
WIRE 16 -1 (-5025 4425)(-4900 4425);
WIRE 16 -1 (-4900 4475)(-4900 4425);
WIRE 16 -1 (-5025 4475)(-4900 4475);
WIRE 16 -1 (-4900 4525)(-4900 4475);
WIRE 16 -1 (-4900 4575)(-4900 4525);
WIRE 16 -1 (-4900 4525)(-5025 4525);
WIRE 16 -1 (-4900 4625)(-4900 4575);
WIRE 16 -1 (-4900 4575)(-5025 4575);
WIRE 16 -1 (-4900 4675)(-4900 4625);
WIRE 16 -1 (-4900 4625)(-5025 4625);
WIRE 16 -1 (-4900 4725)(-4900 4675);
WIRE 16 -1 (-4900 4675)(-5025 4675);
WIRE 16 -1 (-4900 4775)(-4900 4725);
WIRE 16 -1 (-4900 4725)(-5025 4725);
WIRE 16 -1 (-4900 4825)(-4900 4775);
WIRE 16 -1 (-4900 4775)(-5025 4775);
WIRE 16 -1 (-5025 4825)(-4900 4825);
WIRE 16 -1 (-4900 4875)(-4900 4825);
WIRE 16 -1 (-4900 4925)(-4900 4875);
WIRE 16 -1 (-5025 4875)(-4900 4875);
WIRE 16 -1 (-4900 4975)(-4900 4925);
WIRE 16 -1 (-4900 4925)(-5025 4925);
WIRE 16 -1 (-4900 5025)(-4900 4975);
WIRE 16 -1 (-4900 4975)(-5025 4975);
WIRE 16 -1 (-4900 5075)(-4900 5025);
WIRE 16 -1 (-4900 5025)(-5025 5025);
WIRE 16 -1 (-4900 5125)(-4900 5075);
WIRE 16 -1 (-4900 5075)(-5025 5075);
WIRE 16 -1 (-4900 5175)(-4900 5125);
WIRE 16 -1 (-4900 5125)(-5025 5125);
WIRE 16 -1 (-4900 5225)(-4900 5175);
WIRE 16 -1 (-4900 5175)(-5025 5175);
WIRE 16 -1 (-5025 5225)(-4900 5225);
WIRE 16 -1 (-4900 5275)(-4900 5225);
WIRE 16 -1 (-5025 5275)(-4900 5275);
WIRE 16 -1 (-4900 5325)(-4900 5275);
WIRE 16 -1 (-4900 5375)(-4900 5325);
WIRE 16 -1 (-4900 5325)(-5025 5325);
WIRE 16 -1 (-4900 5425)(-4900 5375);
WIRE 16 -1 (-4900 5375)(-5025 5375);
WIRE 16 -1 (-4900 5475)(-4900 5425);
WIRE 16 -1 (-4900 5425)(-5025 5425);
WIRE 16 -1 (-4900 5525)(-4900 5475);
WIRE 16 -1 (-4900 5475)(-5025 5475);
WIRE 16 -1 (-4900 5575)(-4900 5525);
WIRE 16 -1 (-4900 5525)(-5025 5525);
WIRE 16 -1 (-4900 5625)(-4900 5575);
WIRE 16 -1 (-4900 5575)(-5025 5575);
WIRE 16 -1 (-5025 5625)(-4900 5625);
WIRE 16 -1 (-4900 5675)(-4900 5625);
WIRE 16 -1 (-4900 5725)(-4900 5675);
WIRE 16 -1 (-5025 5675)(-4900 5675);
WIRE 16 -1 (-4900 5775)(-4900 5725);
WIRE 16 -1 (-4900 5725)(-5025 5725);
WIRE 16 -1 (-4900 5825)(-4900 5775);
WIRE 16 -1 (-4900 5775)(-5025 5775);
WIRE 16 -1 (-4900 5875)(-4900 5825);
WIRE 16 -1 (-4900 5825)(-5025 5825);
WIRE 16 -1 (-4900 5925)(-4900 5875);
WIRE 16 -1 (-4900 5875)(-5025 5875);
WIRE 16 -1 (-4900 5975)(-4900 5925);
WIRE 16 -1 (-4900 5925)(-5025 5925);
WIRE 16 -1 (-4900 6025)(-4900 5975);
WIRE 16 -1 (-4900 5975)(-5025 5975);
WIRE 16 -1 (-5025 6025)(-4900 6025);
WIRE 16 -1 (-4900 6075)(-4900 6025);
WIRE 16 -1 (-5025 6075)(-4900 6075);
WIRE 16 -1 (-4900 6125)(-4900 6075);
WIRE 16 -1 (-5025 6125)(-4900 6125);
WIRE 16 -1 (-4900 6175)(-4900 6125);
WIRE 16 -1 (-4900 6225)(-4900 6175);
WIRE 16 -1 (-5025 6175)(-4900 6175);
WIRE 16 -1 (-5025 6225)(-4900 6225);
WIRE 16 -1 (-4900 6275)(-4900 6225);
WIRE 16 -1 (-5025 6275)(-4900 6275);
WIRE 16 -1 (-4900 6325)(-4900 6275);
WIRE 16 -1 (-5025 6325)(-4900 6325);
WIRE 16 -1 (-4750 600)(-4625 600);
WIRE 16 -1 (-4750 650)(-4750 600);
WIRE 16 -1 (-4750 600)(-4750 550);
WIRE 16 -1 (-4750 650)(-4625 650);
WIRE 16 -1 (-4750 700)(-4750 650);
WIRE 16 -1 (-4750 700)(-4625 700);
WIRE 16 -1 (-4750 750)(-4750 700);
WIRE 16 -1 (-4750 800)(-4750 750);
WIRE 16 -1 (-4625 750)(-4750 750);
WIRE 16 -1 (-4750 800)(-4625 800);
WIRE 16 -1 (-4750 850)(-4750 800);
WIRE 16 -1 (-4750 850)(-4625 850);
WIRE 16 -1 (-4750 900)(-4750 850);
WIRE 16 -1 (-4750 900)(-4625 900);
WIRE 16 -1 (-4750 950)(-4750 900);
WIRE 16 -1 (-4750 950)(-4625 950);
WIRE 16 -1 (-4750 1000)(-4750 950);
WIRE 16 -1 (-4750 1050)(-4750 1000);
WIRE 16 -1 (-4625 1000)(-4750 1000);
WIRE 16 -1 (-4750 1050)(-4625 1050);
WIRE 16 -1 (-4750 1100)(-4750 1050);
WIRE 16 -1 (-4750 1100)(-4625 1100);
WIRE 16 -1 (-4750 1150)(-4750 1100);
WIRE 16 -1 (-4750 1150)(-4625 1150);
WIRE 16 -1 (-4750 1200)(-4750 1150);
WIRE 16 -1 (-4750 1200)(-4625 1200);
WIRE 16 -1 (-4750 1250)(-4750 1200);
WIRE 16 -1 (-4750 1300)(-4750 1250);
WIRE 16 -1 (-4750 1250)(-4625 1250);
WIRE 16 -1 (-4625 1300)(-4750 1300);
WIRE 16 -1 (-4750 1350)(-4750 1300);
WIRE 16 -1 (-4750 1350)(-4625 1350);
WIRE 16 -1 (-4750 1400)(-4750 1350);
WIRE 16 -1 (-4750 1400)(-4625 1400);
WIRE 16 -1 (-4750 1450)(-4750 1400);
WIRE 16 -1 (-4750 1450)(-4625 1450);
WIRE 16 -1 (-4750 1500)(-4750 1450);
WIRE 16 -1 (-4750 1550)(-4750 1500);
WIRE 16 -1 (-4750 1500)(-4625 1500);
WIRE 16 -1 (-4625 1550)(-4750 1550);
WIRE 16 -1 (-4750 1600)(-4750 1550);
WIRE 16 -1 (-4750 1600)(-4625 1600);
WIRE 16 -1 (-4750 1650)(-4750 1600);
WIRE 16 -1 (-4750 1650)(-4625 1650);
WIRE 16 -1 (-4750 1700)(-4750 1650);
WIRE 16 -1 (-4750 1700)(-4625 1700);
WIRE 16 -1 (-4750 1750)(-4750 1700);
WIRE 16 -1 (-4750 1800)(-4750 1750);
WIRE 16 -1 (-4750 1750)(-4625 1750);
WIRE 16 -1 (-4625 1800)(-4750 1800);
WIRE 16 -1 (-4750 1850)(-4750 1800);
WIRE 16 -1 (-4750 1850)(-4625 1850);
WIRE 16 -1 (-4750 1900)(-4750 1850);
WIRE 16 -1 (-4750 1900)(-4625 1900);
WIRE 16 -1 (-4750 1950)(-4750 1900);
WIRE 16 -1 (-4750 1950)(-4625 1950);
WIRE 16 -1 (-4750 2000)(-4750 1950);
WIRE 16 -1 (-4750 2050)(-4750 2000);
WIRE 16 -1 (-4750 2000)(-4625 2000);
WIRE 16 -1 (-4625 2050)(-4750 2050);
WIRE 16 -1 (-4750 2100)(-4750 2050);
WIRE 16 -1 (-4750 2100)(-4625 2100);
WIRE 16 -1 (-4750 2150)(-4750 2100);
WIRE 16 -1 (-4750 2150)(-4625 2150);
WIRE 16 -1 (-4750 2200)(-4750 2150);
WIRE 16 -1 (-4750 2200)(-4625 2200);
WIRE 16 -1 (-4750 2250)(-4750 2200);
WIRE 16 -1 (-4750 2250)(-4625 2250);
WIRE 16 -1 (-4750 2300)(-4750 2250);
WIRE 16 -1 (-4750 2350)(-4750 2300);
WIRE 16 -1 (-4625 2300)(-4750 2300);
WIRE 16 -1 (-4750 2350)(-4625 2350);
WIRE 16 -1 (-4750 2400)(-4750 2350);
WIRE 16 -1 (-4750 2400)(-4625 2400);
WIRE 16 -1 (-4750 2450)(-4750 2400);
WIRE 16 -1 (-4750 2450)(-4625 2450);
WIRE 16 -1 (-4750 2500)(-4750 2450);
WIRE 16 -1 (-4750 2500)(-4625 2500);
WIRE 16 -1 (-4750 2550)(-4750 2500);
WIRE 16 -1 (-4750 2600)(-4750 2550);
WIRE 16 -1 (-4625 2550)(-4750 2550);
WIRE 16 -1 (-4750 2600)(-4625 2600);
WIRE 16 -1 (-4750 2650)(-4750 2600);
WIRE 16 -1 (-4750 2650)(-4625 2650);
WIRE 16 -1 (-4750 2700)(-4750 2650);
WIRE 16 -1 (-4750 2700)(-4625 2700);
WIRE 16 -1 (-4750 2750)(-4750 2700);
WIRE 16 -1 (-4750 2750)(-4625 2750);
WIRE 16 -1 (-4750 2800)(-4750 2750);
WIRE 16 -1 (-4750 2850)(-4750 2800);
WIRE 16 -1 (-4625 2800)(-4750 2800);
WIRE 16 -1 (-4750 2850)(-4625 2850);
WIRE 16 -1 (-4750 2900)(-4750 2850);
WIRE 16 -1 (-4750 2900)(-4625 2900);
WIRE 16 -1 (-4750 2950)(-4750 2900);
WIRE 16 -1 (-4750 2950)(-4625 2950);
WIRE 16 -1 (-4750 3000)(-4750 2950);
WIRE 16 -1 (-4750 3000)(-4625 3000);
WIRE 16 -1 (-4750 3050)(-4750 3000);
WIRE 16 -1 (-4750 3100)(-4750 3050);
WIRE 16 -1 (-4625 3050)(-4750 3050);
WIRE 16 -1 (-4750 3100)(-4625 3100);
WIRE 16 -1 (-4750 3150)(-4750 3100);
WIRE 16 -1 (-4750 3150)(-4625 3150);
WIRE 16 -1 (-4750 3200)(-4750 3150);
WIRE 16 -1 (-4750 3200)(-4625 3200);
WIRE 16 -1 (-4750 3250)(-4750 3200);
WIRE 16 -1 (-4750 3250)(-4625 3250);
WIRE 16 -1 (-4750 3300)(-4750 3250);
WIRE 16 -1 (-4750 3350)(-4750 3300);
WIRE 16 -1 (-4750 3300)(-4625 3300);
WIRE 16 -1 (-4625 3350)(-4750 3350);
WIRE 16 -1 (-4750 3400)(-4750 3350);
WIRE 16 -1 (-4750 3400)(-4625 3400);
WIRE 16 -1 (-4750 3450)(-4750 3400);
WIRE 16 -1 (-4750 3450)(-4625 3450);
WIRE 16 -1 (-4750 3500)(-4750 3450);
WIRE 16 -1 (-4750 3500)(-4625 3500);
WIRE 16 -1 (-4750 3550)(-4750 3500);
WIRE 16 -1 (-4750 3600)(-4750 3550);
WIRE 16 -1 (-4750 3550)(-4625 3550);
WIRE 16 -1 (-4625 3600)(-4750 3600);
WIRE 16 -1 (-4750 3650)(-4750 3600);
WIRE 16 -1 (-4750 3650)(-4625 3650);
WIRE 16 -1 (-4750 3700)(-4750 3650);
WIRE 16 -1 (-4750 3700)(-4625 3700);
WIRE 16 -1 (-4750 3750)(-4750 3700);
WIRE 16 -1 (-4750 3750)(-4625 3750);
WIRE 16 -1 (-4750 3800)(-4750 3750);
WIRE 16 -1 (-4750 3850)(-4750 3800);
WIRE 16 -1 (-4750 3800)(-4625 3800);
WIRE 16 -1 (-4625 3850)(-4750 3850);
WIRE 16 -1 (-4750 3900)(-4750 3850);
WIRE 16 -1 (-4750 3900)(-4625 3900);
WIRE 16 -1 (-4750 3950)(-4750 3900);
WIRE 16 -1 (-4750 3950)(-4625 3950);
WIRE 16 -1 (-4750 4000)(-4750 3950);
WIRE 16 -1 (-4750 4000)(-4625 4000);
WIRE 16 -1 (-4750 4050)(-4750 4000);
WIRE 16 -1 (-4750 4100)(-4750 4050);
WIRE 16 -1 (-4750 4050)(-4625 4050);
WIRE 16 -1 (-4625 4100)(-4750 4100);
WIRE 16 -1 (-4750 4150)(-4750 4100);
WIRE 16 -1 (-4750 4150)(-4625 4150);
WIRE 16 -1 (-4750 4200)(-4750 4150);
WIRE 16 -1 (-4750 4200)(-4625 4200);
WIRE 16 -1 (-4750 4250)(-4750 4200);
WIRE 16 -1 (-4750 4250)(-4625 4250);
WIRE 16 -1 (-4750 4300)(-4750 4250);
WIRE 16 -1 (-4750 4300)(-4625 4300);
WIRE 16 -1 (-4750 4350)(-4750 4300);
WIRE 16 -1 (-4750 4400)(-4750 4350);
WIRE 16 -1 (-4625 4350)(-4750 4350);
WIRE 16 -1 (-4750 4400)(-4625 4400);
WIRE 16 -1 (-4750 4450)(-4750 4400);
WIRE 16 -1 (-4750 4450)(-4625 4450);
WIRE 16 -1 (-4750 4500)(-4750 4450);
WIRE 16 -1 (-4750 4500)(-4625 4500);
WIRE 16 -1 (-4750 4550)(-4750 4500);
WIRE 16 -1 (-4750 4550)(-4625 4550);
WIRE 16 -1 (-4750 4600)(-4750 4550);
WIRE 16 -1 (-4750 4650)(-4750 4600);
WIRE 16 -1 (-4625 4600)(-4750 4600);
WIRE 16 -1 (-4750 4650)(-4625 4650);
WIRE 16 -1 (-4750 4700)(-4750 4650);
WIRE 16 -1 (-4750 4700)(-4625 4700);
WIRE 16 -1 (-4750 4750)(-4750 4700);
WIRE 16 -1 (-4750 4750)(-4625 4750);
WIRE 16 -1 (-4750 4800)(-4750 4750);
WIRE 16 -1 (-4750 4800)(-4625 4800);
WIRE 16 -1 (-4750 4850)(-4750 4800);
WIRE 16 -1 (-4750 4900)(-4750 4850);
WIRE 16 -1 (-4625 4850)(-4750 4850);
WIRE 16 -1 (-4750 4900)(-4625 4900);
WIRE 16 -1 (-4750 4950)(-4750 4900);
WIRE 16 -1 (-4750 4950)(-4625 4950);
WIRE 16 -1 (-4750 5000)(-4750 4950);
WIRE 16 -1 (-4750 5000)(-4625 5000);
WIRE 16 -1 (-4750 5050)(-4750 5000);
WIRE 16 -1 (-4750 5050)(-4625 5050);
WIRE 16 -1 (-4750 5100)(-4750 5050);
WIRE 16 -1 (-4750 5150)(-4750 5100);
WIRE 16 -1 (-4625 5100)(-4750 5100);
WIRE 16 -1 (-4750 5150)(-4625 5150);
WIRE 16 -1 (-4750 5200)(-4750 5150);
WIRE 16 -1 (-4750 5200)(-4625 5200);
WIRE 16 -1 (-4750 5250)(-4750 5200);
WIRE 16 -1 (-4750 5250)(-4625 5250);
WIRE 16 -1 (-4750 5300)(-4750 5250);
WIRE 16 -1 (-4750 5300)(-4625 5300);
WIRE 16 -1 (-4750 5350)(-4750 5300);
WIRE 16 -1 (-4750 5400)(-4750 5350);
WIRE 16 -1 (-4750 5350)(-4625 5350);
WIRE 16 -1 (-4625 5400)(-4750 5400);
WIRE 16 -1 (-4750 5450)(-4750 5400);
WIRE 16 -1 (-4750 5450)(-4625 5450);
WIRE 16 -1 (-4750 5500)(-4750 5450);
WIRE 16 -1 (-4750 5500)(-4625 5500);
WIRE 16 -1 (-4750 5550)(-4750 5500);
WIRE 16 -1 (-4750 5550)(-4625 5550);
WIRE 16 -1 (-4750 5600)(-4750 5550);
WIRE 16 -1 (-4750 5650)(-4750 5600);
WIRE 16 -1 (-4750 5600)(-4625 5600);
WIRE 16 -1 (-4625 5650)(-4750 5650);
WIRE 16 -1 (-4750 5700)(-4750 5650);
WIRE 16 -1 (-4750 5700)(-4625 5700);
WIRE 16 -1 (-4750 5750)(-4750 5700);
WIRE 16 -1 (-4750 5750)(-4625 5750);
WIRE 16 -1 (-4750 5800)(-4750 5750);
WIRE 16 -1 (-4750 5800)(-4625 5800);
WIRE 16 -1 (-4750 5850)(-4750 5800);
WIRE 16 -1 (-4750 5900)(-4750 5850);
WIRE 16 -1 (-4750 5850)(-4625 5850);
WIRE 16 -1 (-4625 5900)(-4750 5900);
WIRE 16 -1 (-4750 5950)(-4750 5900);
WIRE 16 -1 (-4750 5950)(-4625 5950);
WIRE 16 -1 (-4750 6000)(-4750 5950);
WIRE 16 -1 (-4750 6000)(-4625 6000);
WIRE 16 -1 (-4750 6050)(-4750 6000);
WIRE 16 -1 (-4750 6050)(-4625 6050);
WIRE 16 -1 (-4750 6100)(-4750 6050);
WIRE 16 -1 (-4750 6150)(-4750 6100);
WIRE 16 -1 (-4750 6100)(-4625 6100);
WIRE 16 -1 (-4625 6150)(-4750 6150);
WIRE 16 -1 (-4750 6200)(-4750 6150);
WIRE 16 -1 (-4750 6200)(-4625 6200);
WIRE 16 -1 (-4750 6250)(-4750 6200);
WIRE 16 -1 (-4750 6250)(-4625 6250);
WIRE 16 -1 (-4750 6300)(-4750 6250);
WIRE 16 -1 (-4750 6300)(-4625 6300);
WIRE 16 -1 (-4750 6350)(-4750 6300);
WIRE 16 -1 (-4750 6400)(-4750 6350);
WIRE 16 -1 (-4750 6350)(-4625 6350);
WIRE 16 -1 (-4750 6400)(-4625 6400);
WIRE 16 -1 (-3400 650)(-3400 600);
WIRE 16 -1 (-3400 700)(-3400 650);
WIRE 16 -1 (-3400 650)(-3525 650);
WIRE 16 -1 (-3400 600)(-3400 575);
WIRE 16 -1 (-3400 600)(-3525 600);
WIRE 16 -1 (-3400 750)(-3400 700);
WIRE 16 -1 (-3400 700)(-3525 700);
WIRE 16 -1 (-3400 800)(-3400 750);
WIRE 16 -1 (-3400 750)(-3525 750);
WIRE 16 -1 (-3400 850)(-3400 800);
WIRE 16 -1 (-3400 800)(-3525 800);
WIRE 16 -1 (-3525 850)(-3400 850);
WIRE 16 -1 (-3400 900)(-3400 850);
WIRE 16 -1 (-3525 900)(-3400 900);
WIRE 16 -1 (-3400 950)(-3400 900);
WIRE 16 -1 (-3400 1000)(-3400 950);
WIRE 16 -1 (-3400 950)(-3525 950);
WIRE 16 -1 (-3400 1050)(-3400 1000);
WIRE 16 -1 (-3400 1000)(-3525 1000);
WIRE 16 -1 (-3400 1100)(-3400 1050);
WIRE 16 -1 (-3400 1050)(-3525 1050);
WIRE 16 -1 (-3400 1150)(-3400 1100);
WIRE 16 -1 (-3400 1100)(-3525 1100);
WIRE 16 -1 (-3400 1200)(-3400 1150);
WIRE 16 -1 (-3400 1150)(-3525 1150);
WIRE 16 -1 (-3400 1250)(-3400 1200);
WIRE 16 -1 (-3400 1200)(-3525 1200);
WIRE 16 -1 (-3525 1250)(-3400 1250);
WIRE 16 -1 (-3400 1300)(-3400 1250);
WIRE 16 -1 (-3400 1350)(-3400 1300);
WIRE 16 -1 (-3525 1300)(-3400 1300);
WIRE 16 -1 (-3400 1400)(-3400 1350);
WIRE 16 -1 (-3400 1350)(-3525 1350);
WIRE 16 -1 (-3400 1450)(-3400 1400);
WIRE 16 -1 (-3400 1400)(-3525 1400);
WIRE 16 -1 (-3400 1500)(-3400 1450);
WIRE 16 -1 (-3400 1450)(-3525 1450);
WIRE 16 -1 (-3400 1550)(-3400 1500);
WIRE 16 -1 (-3400 1500)(-3525 1500);
WIRE 16 -1 (-3400 1600)(-3400 1550);
WIRE 16 -1 (-3400 1550)(-3525 1550);
WIRE 16 -1 (-3400 1650)(-3400 1600);
WIRE 16 -1 (-3400 1600)(-3525 1600);
WIRE 16 -1 (-3525 1650)(-3400 1650);
WIRE 16 -1 (-3400 1700)(-3400 1650);
WIRE 16 -1 (-3525 1700)(-3400 1700);
WIRE 16 -1 (-3400 1750)(-3400 1700);
WIRE 16 -1 (-3400 1800)(-3400 1750);
WIRE 16 -1 (-3400 1750)(-3525 1750);
WIRE 16 -1 (-3400 1850)(-3400 1800);
WIRE 16 -1 (-3400 1800)(-3525 1800);
WIRE 16 -1 (-3400 1900)(-3400 1850);
WIRE 16 -1 (-3400 1850)(-3525 1850);
WIRE 16 -1 (-3400 1950)(-3400 1900);
WIRE 16 -1 (-3400 1900)(-3525 1900);
WIRE 16 -1 (-3400 2000)(-3400 1950);
WIRE 16 -1 (-3400 1950)(-3525 1950);
WIRE 16 -1 (-3400 2050)(-3400 2000);
WIRE 16 -1 (-3400 2000)(-3525 2000);
WIRE 16 -1 (-3400 2100)(-3400 2050);
WIRE 16 -1 (-3525 2050)(-3400 2050);
WIRE 16 -1 (-3525 2100)(-3400 2100);
WIRE 16 -1 (-3400 2150)(-3400 2100);
WIRE 16 -1 (-3400 2200)(-3400 2150);
WIRE 16 -1 (-3400 2150)(-3525 2150);
WIRE 16 -1 (-3400 2250)(-3400 2200);
WIRE 16 -1 (-3400 2200)(-3525 2200);
WIRE 16 -1 (-3400 2300)(-3400 2250);
WIRE 16 -1 (-3400 2250)(-3525 2250);
WIRE 16 -1 (-3400 2350)(-3400 2300);
WIRE 16 -1 (-3400 2300)(-3525 2300);
WIRE 16 -1 (-3400 2400)(-3400 2350);
WIRE 16 -1 (-3400 2350)(-3525 2350);
WIRE 16 -1 (-3400 2450)(-3400 2400);
WIRE 16 -1 (-3400 2400)(-3525 2400);
WIRE 16 -1 (-3525 2450)(-3400 2450);
WIRE 16 -1 (-3400 2500)(-3400 2450);
WIRE 16 -1 (-3525 2500)(-3400 2500);
WIRE 16 -1 (-3400 2550)(-3400 2500);
WIRE 16 -1 (-3400 2600)(-3400 2550);
WIRE 16 -1 (-3400 2550)(-3525 2550);
WIRE 16 -1 (-3400 2650)(-3400 2600);
WIRE 16 -1 (-3400 2600)(-3525 2600);
WIRE 16 -1 (-3400 2700)(-3400 2650);
WIRE 16 -1 (-3400 2650)(-3525 2650);
WIRE 16 -1 (-3400 2750)(-3400 2700);
WIRE 16 -1 (-3400 2700)(-3525 2700);
WIRE 16 -1 (-3400 2800)(-3400 2750);
WIRE 16 -1 (-3400 2750)(-3525 2750);
WIRE 16 -1 (-3400 2850)(-3400 2800);
WIRE 16 -1 (-3400 2800)(-3525 2800);
WIRE 16 -1 (-3400 2900)(-3400 2850);
WIRE 16 -1 (-3525 2850)(-3400 2850);
WIRE 16 -1 (-3525 2900)(-3400 2900);
WIRE 16 -1 (-3400 2950)(-3400 2900);
WIRE 16 -1 (-3400 3000)(-3400 2950);
WIRE 16 -1 (-3400 2950)(-3525 2950);
WIRE 16 -1 (-3400 3050)(-3400 3000);
WIRE 16 -1 (-3400 3000)(-3525 3000);
WIRE 16 -1 (-3400 3100)(-3400 3050);
WIRE 16 -1 (-3400 3050)(-3525 3050);
WIRE 16 -1 (-3400 3150)(-3400 3100);
WIRE 16 -1 (-3400 3100)(-3525 3100);
WIRE 16 -1 (-3400 3200)(-3400 3150);
WIRE 16 -1 (-3400 3150)(-3525 3150);
WIRE 16 -1 (-3400 3250)(-3400 3200);
WIRE 16 -1 (-3400 3200)(-3525 3200);
WIRE 16 -1 (-3525 3250)(-3400 3250);
WIRE 16 -1 (-3400 3300)(-3400 3250);
WIRE 16 -1 (-3525 3300)(-3400 3300);
WIRE 16 -1 (-3400 3350)(-3400 3300);
WIRE 16 -1 (-3400 3400)(-3400 3350);
WIRE 16 -1 (-3400 3350)(-3525 3350);
WIRE 16 -1 (-3400 3450)(-3400 3400);
WIRE 16 -1 (-3400 3400)(-3525 3400);
WIRE 16 -1 (-3400 3500)(-3400 3450);
WIRE 16 -1 (-3400 3450)(-3525 3450);
WIRE 16 -1 (-3400 3550)(-3400 3500);
WIRE 16 -1 (-3400 3500)(-3525 3500);
WIRE 16 -1 (-3400 3600)(-3400 3550);
WIRE 16 -1 (-3400 3550)(-3525 3550);
WIRE 16 -1 (-3400 3650)(-3400 3600);
WIRE 16 -1 (-3400 3600)(-3525 3600);
WIRE 16 -1 (-3525 3650)(-3400 3650);
WIRE 16 -1 (-3400 3700)(-3400 3650);
WIRE 16 -1 (-3525 3700)(-3400 3700);
WIRE 16 -1 (-3400 3750)(-3400 3700);
WIRE 16 -1 (-3400 3800)(-3400 3750);
WIRE 16 -1 (-3400 3750)(-3525 3750);
WIRE 16 -1 (-3400 3850)(-3400 3800);
WIRE 16 -1 (-3400 3800)(-3525 3800);
WIRE 16 -1 (-3400 3900)(-3400 3850);
WIRE 16 -1 (-3400 3850)(-3525 3850);
WIRE 16 -1 (-3400 3950)(-3400 3900);
WIRE 16 -1 (-3400 3900)(-3525 3900);
WIRE 16 -1 (-3400 4000)(-3400 3950);
WIRE 16 -1 (-3400 3950)(-3525 3950);
WIRE 16 -1 (-3400 4050)(-3400 4000);
WIRE 16 -1 (-3400 4000)(-3525 4000);
WIRE 16 -1 (-3525 4050)(-3400 4050);
WIRE 16 -1 (-3400 4100)(-3400 4050);
WIRE 16 -1 (-3400 4150)(-3400 4100);
WIRE 16 -1 (-3525 4100)(-3400 4100);
WIRE 16 -1 (-3400 4200)(-3400 4150);
WIRE 16 -1 (-3400 4150)(-3525 4150);
WIRE 16 -1 (-3400 4250)(-3400 4200);
WIRE 16 -1 (-3400 4200)(-3525 4200);
WIRE 16 -1 (-3400 4300)(-3400 4250);
WIRE 16 -1 (-3400 4250)(-3525 4250);
WIRE 16 -1 (-3400 4350)(-3400 4300);
WIRE 16 -1 (-3400 4300)(-3525 4300);
WIRE 16 -1 (-3400 4400)(-3400 4350);
WIRE 16 -1 (-3400 4350)(-3525 4350);
WIRE 16 -1 (-3400 4450)(-3400 4400);
WIRE 16 -1 (-3400 4400)(-3525 4400);
WIRE 16 -1 (-3525 4450)(-3400 4450);
WIRE 16 -1 (-3400 4500)(-3400 4450);
WIRE 16 -1 (-3525 4500)(-3400 4500);
WIRE 16 -1 (-3400 4550)(-3400 4500);
WIRE 16 -1 (-3400 4600)(-3400 4550);
WIRE 16 -1 (-3400 4550)(-3525 4550);
WIRE 16 -1 (-3400 4650)(-3400 4600);
WIRE 16 -1 (-3400 4600)(-3525 4600);
WIRE 16 -1 (-3400 4700)(-3400 4650);
WIRE 16 -1 (-3400 4650)(-3525 4650);
WIRE 16 -1 (-3400 4750)(-3400 4700);
WIRE 16 -1 (-3400 4700)(-3525 4700);
WIRE 16 -1 (-3400 4800)(-3400 4750);
WIRE 16 -1 (-3400 4750)(-3525 4750);
WIRE 16 -1 (-3400 4850)(-3400 4800);
WIRE 16 -1 (-3400 4800)(-3525 4800);
WIRE 16 -1 (-3525 4850)(-3400 4850);
WIRE 16 -1 (-3400 4900)(-3400 4850);
WIRE 16 -1 (-3400 4950)(-3400 4900);
WIRE 16 -1 (-3525 4900)(-3400 4900);
WIRE 16 -1 (-3400 5000)(-3400 4950);
WIRE 16 -1 (-3400 4950)(-3525 4950);
WIRE 16 -1 (-3400 5050)(-3400 5000);
WIRE 16 -1 (-3400 5000)(-3525 5000);
WIRE 16 -1 (-3400 5100)(-3400 5050);
WIRE 16 -1 (-3400 5050)(-3525 5050);
WIRE 16 -1 (-3400 5150)(-3400 5100);
WIRE 16 -1 (-3400 5100)(-3525 5100);
WIRE 16 -1 (-3400 5200)(-3400 5150);
WIRE 16 -1 (-3400 5150)(-3525 5150);
WIRE 16 -1 (-3400 5250)(-3400 5200);
WIRE 16 -1 (-3400 5200)(-3525 5200);
WIRE 16 -1 (-3525 5250)(-3400 5250);
WIRE 16 -1 (-3400 5300)(-3400 5250);
WIRE 16 -1 (-3525 5300)(-3400 5300);
WIRE 16 -1 (-3400 5350)(-3400 5300);
WIRE 16 -1 (-3400 5400)(-3400 5350);
WIRE 16 -1 (-3400 5350)(-3525 5350);
WIRE 16 -1 (-3400 5450)(-3400 5400);
WIRE 16 -1 (-3400 5400)(-3525 5400);
WIRE 16 -1 (-3400 5500)(-3400 5450);
WIRE 16 -1 (-3400 5450)(-3525 5450);
WIRE 16 -1 (-3400 5550)(-3400 5500);
WIRE 16 -1 (-3400 5500)(-3525 5500);
WIRE 16 -1 (-3400 5600)(-3400 5550);
WIRE 16 -1 (-3400 5550)(-3525 5550);
WIRE 16 -1 (-3400 5650)(-3400 5600);
WIRE 16 -1 (-3400 5600)(-3525 5600);
WIRE 16 -1 (-3400 5700)(-3400 5650);
WIRE 16 -1 (-3525 5650)(-3400 5650);
WIRE 16 -1 (-3525 5700)(-3400 5700);
WIRE 16 -1 (-3400 5750)(-3400 5700);
WIRE 16 -1 (-3400 5800)(-3400 5750);
WIRE 16 -1 (-3400 5750)(-3525 5750);
WIRE 16 -1 (-3400 5850)(-3400 5800);
WIRE 16 -1 (-3400 5800)(-3525 5800);
WIRE 16 -1 (-3400 5900)(-3400 5850);
WIRE 16 -1 (-3400 5850)(-3525 5850);
WIRE 16 -1 (-3400 5950)(-3400 5900);
WIRE 16 -1 (-3400 5900)(-3525 5900);
WIRE 16 -1 (-3400 6000)(-3400 5950);
WIRE 16 -1 (-3400 5950)(-3525 5950);
WIRE 16 -1 (-3400 6050)(-3400 6000);
WIRE 16 -1 (-3400 6000)(-3525 6000);
WIRE 16 -1 (-3525 6050)(-3400 6050);
WIRE 16 -1 (-3400 6100)(-3400 6050);
WIRE 16 -1 (-3525 6100)(-3400 6100);
WIRE 16 -1 (-3400 6150)(-3400 6100);
WIRE 16 -1 (-3400 6200)(-3400 6150);
WIRE 16 -1 (-3525 6150)(-3400 6150);
WIRE 16 -1 (-3525 6200)(-3400 6200);
WIRE 16 -1 (-3400 6250)(-3400 6200);
WIRE 16 -1 (-3525 6250)(-3400 6250);
WIRE 16 -1 (-3400 6300)(-3400 6250);
WIRE 16 -1 (-3525 6300)(-3400 6300);
WIRE 16 -1 (-3400 6350)(-3400 6300);
WIRE 16 -1 (-3525 6350)(-3400 6350);
WIRE 16 -1 (-3400 6400)(-3400 6350);
WIRE 16 -1 (-3525 6400)(-3400 6400);
WIRE 16 -1 (-3150 550)(-3250 550);
WIRE 16 -1 (-3250 600)(-3250 550);
WIRE 16 -1 (-3250 550)(-3250 500);
WIRE 16 -1 (-3150 600)(-3250 600);
WIRE 16 -1 (-3250 650)(-3250 600);
WIRE 16 -1 (-3150 650)(-3250 650);
WIRE 16 -1 (-3250 700)(-3250 650);
WIRE 16 -1 (-3150 700)(-3250 700);
WIRE 16 -1 (-3250 750)(-3250 700);
WIRE 16 -1 (-3250 800)(-3250 750);
WIRE 16 -1 (-3150 750)(-3250 750);
WIRE 16 -1 (-3150 800)(-3250 800);
WIRE 16 -1 (-3250 850)(-3250 800);
WIRE 16 -1 (-3150 850)(-3250 850);
WIRE 16 -1 (-3250 900)(-3250 850);
WIRE 16 -1 (-3150 900)(-3250 900);
WIRE 16 -1 (-3250 950)(-3250 900);
WIRE 16 -1 (-3150 950)(-3250 950);
WIRE 16 -1 (-3250 1000)(-3250 950);
WIRE 16 -1 (-3250 1050)(-3250 1000);
WIRE 16 -1 (-3250 1000)(-3150 1000);
WIRE 16 -1 (-3250 1050)(-3150 1050);
WIRE 16 -1 (-3250 1100)(-3250 1050);
WIRE 16 -1 (-3250 1100)(-3150 1100);
WIRE 16 -1 (-3250 1150)(-3250 1100);
WIRE 16 -1 (-3250 1150)(-3150 1150);
WIRE 16 -1 (-3250 1200)(-3250 1150);
WIRE 16 -1 (-3250 1200)(-3150 1200);
WIRE 16 -1 (-3250 1250)(-3250 1200);
WIRE 16 -1 (-3250 1300)(-3250 1250);
WIRE 16 -1 (-3250 1250)(-3150 1250);
WIRE 16 -1 (-3150 1300)(-3250 1300);
WIRE 16 -1 (-3250 1350)(-3250 1300);
WIRE 16 -1 (-3150 1350)(-3250 1350);
WIRE 16 -1 (-3250 1400)(-3250 1350);
WIRE 16 -1 (-3250 1400)(-3150 1400);
WIRE 16 -1 (-3250 1450)(-3250 1400);
WIRE 16 -1 (-3250 1450)(-3150 1450);
WIRE 16 -1 (-3250 1500)(-3250 1450);
WIRE 16 -1 (-3250 1550)(-3250 1500);
WIRE 16 -1 (-3250 1500)(-3150 1500);
WIRE 16 -1 (-3250 1550)(-3150 1550);
WIRE 16 -1 (-3250 1600)(-3250 1550);
WIRE 16 -1 (-3250 1600)(-3150 1600);
WIRE 16 -1 (-3250 1650)(-3250 1600);
WIRE 16 -1 (-3250 1650)(-3150 1650);
WIRE 16 -1 (-3250 1700)(-3250 1650);
WIRE 16 -1 (-3150 1700)(-3250 1700);
WIRE 16 -1 (-3250 1750)(-3250 1700);
WIRE 16 -1 (-3250 1800)(-3250 1750);
WIRE 16 -1 (-3150 1750)(-3250 1750);
WIRE 16 -1 (-3250 1800)(-3150 1800);
WIRE 16 -1 (-3250 1850)(-3250 1800);
WIRE 16 -1 (-3250 1850)(-3150 1850);
WIRE 16 -1 (-3250 1900)(-3250 1850);
WIRE 16 -1 (-3250 1900)(-3150 1900);
WIRE 16 -1 (-3250 1950)(-3250 1900);
WIRE 16 -1 (-3250 1950)(-3150 1950);
WIRE 16 -1 (-3250 2000)(-3250 1950);
WIRE 16 -1 (-3250 2050)(-3250 2000);
WIRE 16 -1 (-3250 2000)(-3150 2000);
WIRE 16 -1 (-3250 2050)(-3150 2050);
WIRE 16 -1 (-3250 2100)(-3250 2050);
WIRE 16 -1 (-3150 2100)(-3250 2100);
WIRE 16 -1 (-3250 2150)(-3250 2100);
WIRE 16 -1 (-3150 2150)(-3250 2150);
WIRE 16 -1 (-3250 2200)(-3250 2150);
WIRE 16 -1 (-3250 2200)(-3150 2200);
WIRE 16 -1 (-3250 2250)(-3250 2200);
WIRE 16 -1 (-3250 2250)(-3150 2250);
WIRE 16 -1 (-3250 2300)(-3250 2250);
WIRE 16 -1 (-3250 2350)(-3250 2300);
WIRE 16 -1 (-3250 2300)(-3150 2300);
WIRE 16 -1 (-3250 2350)(-3150 2350);
WIRE 16 -1 (-3250 2400)(-3250 2350);
WIRE 16 -1 (-3250 2400)(-3150 2400);
WIRE 16 -1 (-3250 2450)(-3250 2400);
WIRE 16 -1 (-3250 2450)(-3150 2450);
WIRE 16 -1 (-3250 2500)(-3250 2450);
WIRE 16 -1 (-3150 2500)(-3250 2500);
WIRE 16 -1 (-3250 2550)(-3250 2500);
WIRE 16 -1 (-3250 2600)(-3250 2550);
WIRE 16 -1 (-3150 2550)(-3250 2550);
WIRE 16 -1 (-3250 2600)(-3150 2600);
WIRE 16 -1 (-3250 2650)(-3250 2600);
WIRE 16 -1 (-3250 2650)(-3150 2650);
WIRE 16 -1 (-3250 2700)(-3250 2650);
WIRE 16 -1 (-3250 2700)(-3150 2700);
WIRE 16 -1 (-3250 2750)(-3250 2700);
WIRE 16 -1 (-3250 2750)(-3150 2750);
WIRE 16 -1 (-3250 2800)(-3250 2750);
WIRE 16 -1 (-3250 2850)(-3250 2800);
WIRE 16 -1 (-3250 2800)(-3150 2800);
WIRE 16 -1 (-3250 2850)(-3150 2850);
WIRE 16 -1 (-3250 2900)(-3250 2850);
WIRE 16 -1 (-3150 2900)(-3250 2900);
WIRE 16 -1 (-3250 2950)(-3250 2900);
WIRE 16 -1 (-3150 2950)(-3250 2950);
WIRE 16 -1 (-3250 3000)(-3250 2950);
WIRE 16 -1 (-3250 3000)(-3150 3000);
WIRE 16 -1 (-3250 3050)(-3250 3000);
WIRE 16 -1 (-3250 3100)(-3250 3050);
WIRE 16 -1 (-3250 3050)(-3150 3050);
WIRE 16 -1 (-3250 3100)(-3150 3100);
WIRE 16 -1 (-3250 3150)(-3250 3100);
WIRE 16 -1 (-3250 3150)(-3150 3150);
WIRE 16 -1 (-3250 3200)(-3250 3150);
WIRE 16 -1 (-3250 3200)(-3150 3200);
WIRE 16 -1 (-3250 3250)(-3250 3200);
WIRE 16 -1 (-3250 3250)(-3150 3250);
WIRE 16 -1 (-3250 3300)(-3250 3250);
WIRE 16 -1 (-3250 3350)(-3250 3300);
WIRE 16 -1 (-3150 3300)(-3250 3300);
WIRE 16 -1 (-3150 3350)(-3250 3350);
WIRE 16 -1 (-3250 3400)(-3250 3350);
WIRE 16 -1 (-3250 3400)(-3150 3400);
WIRE 16 -1 (-3250 3450)(-3250 3400);
WIRE 16 -1 (-3250 3450)(-3150 3450);
WIRE 16 -1 (-3250 3500)(-3250 3450);
WIRE 16 -1 (-3250 3500)(-3150 3500);
WIRE 16 -1 (-3250 3550)(-3250 3500);
WIRE 16 -1 (-3250 3600)(-3250 3550);
WIRE 16 -1 (-3250 3550)(-3150 3550);
WIRE 16 -1 (-3250 3600)(-3150 3600);
WIRE 16 -1 (-3250 3650)(-3250 3600);
WIRE 16 -1 (-3250 3650)(-3150 3650);
WIRE 16 -1 (-3250 3700)(-3250 3650);
WIRE 16 -1 (-3150 3700)(-3250 3700);
WIRE 16 -1 (-3250 3750)(-3250 3700);
WIRE 16 -1 (-3150 3750)(-3250 3750);
WIRE 16 -1 (-3250 3800)(-3250 3750);
WIRE 16 -1 (-3250 3850)(-3250 3800);
WIRE 16 -1 (-3250 3800)(-3150 3800);
WIRE 16 -1 (-3250 3850)(-3150 3850);
WIRE 16 -1 (-3250 3900)(-3250 3850);
WIRE 16 -1 (-3250 3900)(-3150 3900);
WIRE 16 -1 (-3250 3950)(-3250 3900);
WIRE 16 -1 (-3250 3950)(-3150 3950);
WIRE 16 -1 (-3250 4000)(-3250 3950);
WIRE 16 -1 (-3250 4000)(-3150 4000);
WIRE 16 -1 (-3250 4050)(-3250 4000);
WIRE 16 -1 (-3250 4100)(-3250 4050);
WIRE 16 -1 (-3250 4050)(-3150 4050);
WIRE 16 -1 (-3150 4100)(-3250 4100);
WIRE 16 -1 (-3250 4150)(-3250 4100);
WIRE 16 -1 (-3150 4150)(-3250 4150);
WIRE 16 -1 (-3250 4200)(-3250 4150);
WIRE 16 -1 (-3250 4200)(-3150 4200);
WIRE 16 -1 (-3250 4250)(-3250 4200);
WIRE 16 -1 (-3250 4250)(-3150 4250);
WIRE 16 -1 (-3250 4300)(-3250 4250);
WIRE 16 -1 (-3250 4300)(-3150 4300);
WIRE 16 -1 (-3250 4350)(-3250 4300);
WIRE 16 -1 (-3250 4400)(-3250 4350);
WIRE 16 -1 (-3250 4350)(-3150 4350);
WIRE 16 -1 (-3250 4400)(-3150 4400);
WIRE 16 -1 (-3250 4450)(-3250 4400);
WIRE 16 -1 (-3250 4450)(-3150 4450);
WIRE 16 -1 (-3250 4500)(-3250 4450);
WIRE 16 -1 (-3150 4500)(-3250 4500);
WIRE 16 -1 (-3250 4550)(-3250 4500);
WIRE 16 -1 (-3150 4550)(-3250 4550);
WIRE 16 -1 (-3250 4600)(-3250 4550);
WIRE 16 -1 (-3250 4650)(-3250 4600);
WIRE 16 -1 (-3250 4600)(-3150 4600);
WIRE 16 -1 (-3250 4650)(-3150 4650);
WIRE 16 -1 (-3250 4700)(-3250 4650);
WIRE 16 -1 (-3250 4700)(-3150 4700);
WIRE 16 -1 (-3250 4750)(-3250 4700);
WIRE 16 -1 (-3250 4750)(-3150 4750);
WIRE 16 -1 (-3250 4800)(-3250 4750);
WIRE 16 -1 (-3250 4800)(-3150 4800);
WIRE 16 -1 (-3250 4850)(-3250 4800);
WIRE 16 -1 (-3250 4900)(-3250 4850);
WIRE 16 -1 (-3250 4850)(-3150 4850);
WIRE 16 -1 (-3150 4900)(-3250 4900);
WIRE 16 -1 (-3250 4950)(-3250 4900);
WIRE 16 -1 (-3150 4950)(-3250 4950);
WIRE 16 -1 (-3250 5000)(-3250 4950);
WIRE 16 -1 (-3250 5000)(-3150 5000);
WIRE 16 -1 (-3250 5050)(-3250 5000);
WIRE 16 -1 (-3250 5050)(-3150 5050);
WIRE 16 -1 (-3250 5100)(-3250 5050);
WIRE 16 -1 (-3250 5150)(-3250 5100);
WIRE 16 -1 (-3250 5100)(-3150 5100);
WIRE 16 -1 (-3250 5150)(-3150 5150);
WIRE 16 -1 (-3250 5200)(-3250 5150);
WIRE 16 -1 (-3250 5200)(-3150 5200);
WIRE 16 -1 (-3250 5250)(-3250 5200);
WIRE 16 -1 (-3250 5250)(-3150 5250);
WIRE 16 -1 (-3250 5300)(-3250 5250);
WIRE 16 -1 (-3150 5300)(-3250 5300);
WIRE 16 -1 (-3250 5350)(-3250 5300);
WIRE 16 -1 (-3250 5400)(-3250 5350);
WIRE 16 -1 (-3150 5350)(-3250 5350);
WIRE 16 -1 (-3250 5400)(-3150 5400);
WIRE 16 -1 (-3250 5450)(-3250 5400);
WIRE 16 -1 (-3250 5450)(-3150 5450);
WIRE 16 -1 (-3250 5500)(-3250 5450);
WIRE 16 -1 (-3250 5500)(-3150 5500);
WIRE 16 -1 (-3250 5550)(-3250 5500);
WIRE 16 -1 (-3250 5550)(-3150 5550);
WIRE 16 -1 (-3250 5600)(-3250 5550);
WIRE 16 -1 (-3250 5650)(-3250 5600);
WIRE 16 -1 (-3250 5600)(-3150 5600);
WIRE 16 -1 (-3250 5650)(-3150 5650);
WIRE 16 -1 (-3250 5700)(-3250 5650);
WIRE 16 -1 (-3150 5700)(-3250 5700);
WIRE 16 -1 (-3250 5750)(-3250 5700);
WIRE 16 -1 (-3150 5750)(-3250 5750);
WIRE 16 -1 (-3250 5800)(-3250 5750);
WIRE 16 -1 (-3250 5800)(-3150 5800);
WIRE 16 -1 (-3250 5850)(-3250 5800);
WIRE 16 -1 (-3250 5900)(-3250 5850);
WIRE 16 -1 (-3250 5850)(-3150 5850);
WIRE 16 -1 (-3250 5900)(-3150 5900);
WIRE 16 -1 (-3250 5950)(-3250 5900);
WIRE 16 -1 (-3250 5950)(-3150 5950);
WIRE 16 -1 (-3250 6000)(-3250 5950);
WIRE 16 -1 (-3250 6000)(-3150 6000);
WIRE 16 -1 (-3250 6050)(-3250 6000);
WIRE 16 -1 (-3250 6050)(-3150 6050);
WIRE 16 -1 (-3250 6100)(-3250 6050);
WIRE 16 -1 (-3250 6150)(-3250 6100);
WIRE 16 -1 (-3150 6100)(-3250 6100);
WIRE 16 -1 (-3150 6150)(-3250 6150);
WIRE 16 -1 (-3250 6200)(-3250 6150);
WIRE 16 -1 (-3250 6200)(-3150 6200);
WIRE 16 -1 (-3250 6250)(-3250 6200);
WIRE 16 -1 (-3250 6250)(-3150 6250);
WIRE 16 -1 (-3250 6300)(-3250 6250);
WIRE 16 -1 (-3250 6300)(-3150 6300);
WIRE 16 -1 (-3250 6350)(-3250 6300);
WIRE 16 -1 (-3250 6400)(-3250 6350);
WIRE 16 -1 (-3250 6350)(-3150 6350);
WIRE 16 -1 (-3250 6400)(-3150 6400);
WIRE 16 -1 (-1925 550)(-1925 525);
WIRE 16 -1 (-1925 600)(-1925 550);
WIRE 16 -1 (-1925 550)(-2050 550);
WIRE 16 -1 (-1925 650)(-1925 600);
WIRE 16 -1 (-1925 600)(-2050 600);
WIRE 16 -1 (-1925 700)(-1925 650);
WIRE 16 -1 (-1925 650)(-2050 650);
WIRE 16 -1 (-1925 750)(-1925 700);
WIRE 16 -1 (-1925 700)(-2050 700);
WIRE 16 -1 (-1925 800)(-1925 750);
WIRE 16 -1 (-1925 750)(-2050 750);
WIRE 16 -1 (-2050 800)(-1925 800);
WIRE 16 -1 (-1925 850)(-1925 800);
WIRE 16 -1 (-2050 850)(-1925 850);
WIRE 16 -1 (-1925 900)(-1925 850);
WIRE 16 -1 (-1925 950)(-1925 900);
WIRE 16 -1 (-1925 900)(-2050 900);
WIRE 16 -1 (-1925 1000)(-1925 950);
WIRE 16 -1 (-1925 950)(-2050 950);
WIRE 16 -1 (-1925 1050)(-1925 1000);
WIRE 16 -1 (-1925 1000)(-2050 1000);
WIRE 16 -1 (-1925 1100)(-1925 1050);
WIRE 16 -1 (-1925 1050)(-2050 1050);
WIRE 16 -1 (-1925 1150)(-1925 1100);
WIRE 16 -1 (-1925 1100)(-2050 1100);
WIRE 16 -1 (-1925 1200)(-1925 1150);
WIRE 16 -1 (-1925 1150)(-2050 1150);
WIRE 16 -1 (-2050 1200)(-1925 1200);
WIRE 16 -1 (-1925 1250)(-1925 1200);
WIRE 16 -1 (-2050 1250)(-1925 1250);
WIRE 16 -1 (-1925 1300)(-1925 1250);
WIRE 16 -1 (-1925 1350)(-1925 1300);
WIRE 16 -1 (-1925 1300)(-2050 1300);
WIRE 16 -1 (-1925 1400)(-1925 1350);
WIRE 16 -1 (-1925 1350)(-2050 1350);
WIRE 16 -1 (-1925 1450)(-1925 1400);
WIRE 16 -1 (-1925 1400)(-2050 1400);
WIRE 16 -1 (-1925 1500)(-1925 1450);
WIRE 16 -1 (-1925 1450)(-2050 1450);
WIRE 16 -1 (-1925 1550)(-1925 1500);
WIRE 16 -1 (-1925 1500)(-2050 1500);
WIRE 16 -1 (-1925 1600)(-1925 1550);
WIRE 16 -1 (-1925 1550)(-2050 1550);
WIRE 16 -1 (-2050 1600)(-1925 1600);
WIRE 16 -1 (-1925 1650)(-1925 1600);
WIRE 16 -1 (-2050 1650)(-1925 1650);
WIRE 16 -1 (-1925 1700)(-1925 1650);
WIRE 16 -1 (-1925 1750)(-1925 1700);
WIRE 16 -1 (-1925 1700)(-2050 1700);
WIRE 16 -1 (-1925 1800)(-1925 1750);
WIRE 16 -1 (-1925 1750)(-2050 1750);
WIRE 16 -1 (-1925 1850)(-1925 1800);
WIRE 16 -1 (-1925 1800)(-2050 1800);
WIRE 16 -1 (-1925 1900)(-1925 1850);
WIRE 16 -1 (-1925 1850)(-2050 1850);
WIRE 16 -1 (-1925 1950)(-1925 1900);
WIRE 16 -1 (-1925 1900)(-2050 1900);
WIRE 16 -1 (-1925 2000)(-1925 1950);
WIRE 16 -1 (-1925 1950)(-2050 1950);
WIRE 16 -1 (-2050 2000)(-1925 2000);
WIRE 16 -1 (-1925 2050)(-1925 2000);
WIRE 16 -1 (-2050 2050)(-1925 2050);
WIRE 16 -1 (-1925 2100)(-1925 2050);
WIRE 16 -1 (-1925 2150)(-1925 2100);
WIRE 16 -1 (-1925 2100)(-2050 2100);
WIRE 16 -1 (-1925 2200)(-1925 2150);
WIRE 16 -1 (-1925 2150)(-2050 2150);
WIRE 16 -1 (-1925 2250)(-1925 2200);
WIRE 16 -1 (-1925 2200)(-2050 2200);
WIRE 16 -1 (-1925 2300)(-1925 2250);
WIRE 16 -1 (-1925 2250)(-2050 2250);
WIRE 16 -1 (-1925 2350)(-1925 2300);
WIRE 16 -1 (-1925 2300)(-2050 2300);
WIRE 16 -1 (-1925 2400)(-1925 2350);
WIRE 16 -1 (-1925 2350)(-2050 2350);
WIRE 16 -1 (-2050 2400)(-1925 2400);
WIRE 16 -1 (-1925 2450)(-1925 2400);
WIRE 16 -1 (-2050 2450)(-1925 2450);
WIRE 16 -1 (-1925 2500)(-1925 2450);
WIRE 16 -1 (-1925 2550)(-1925 2500);
WIRE 16 -1 (-1925 2500)(-2050 2500);
WIRE 16 -1 (-1925 2600)(-1925 2550);
WIRE 16 -1 (-1925 2550)(-2050 2550);
WIRE 16 -1 (-1925 2650)(-1925 2600);
WIRE 16 -1 (-1925 2600)(-2050 2600);
WIRE 16 -1 (-1925 2700)(-1925 2650);
WIRE 16 -1 (-1925 2650)(-2050 2650);
WIRE 16 -1 (-1925 2750)(-1925 2700);
WIRE 16 -1 (-1925 2700)(-2050 2700);
WIRE 16 -1 (-1925 2800)(-1925 2750);
WIRE 16 -1 (-1925 2750)(-2050 2750);
WIRE 16 -1 (-2050 2800)(-1925 2800);
WIRE 16 -1 (-1925 2850)(-1925 2800);
WIRE 16 -1 (-2050 2850)(-1925 2850);
WIRE 16 -1 (-1925 2900)(-1925 2850);
WIRE 16 -1 (-1925 2950)(-1925 2900);
WIRE 16 -1 (-1925 2900)(-2050 2900);
WIRE 16 -1 (-1925 3000)(-1925 2950);
WIRE 16 -1 (-1925 2950)(-2050 2950);
WIRE 16 -1 (-1925 3050)(-1925 3000);
WIRE 16 -1 (-1925 3000)(-2050 3000);
WIRE 16 -1 (-1925 3100)(-1925 3050);
WIRE 16 -1 (-1925 3050)(-2050 3050);
WIRE 16 -1 (-1925 3150)(-1925 3100);
WIRE 16 -1 (-1925 3100)(-2050 3100);
WIRE 16 -1 (-1925 3200)(-1925 3150);
WIRE 16 -1 (-1925 3150)(-2050 3150);
WIRE 16 -1 (-2050 3200)(-1925 3200);
WIRE 16 -1 (-1925 3250)(-1925 3200);
WIRE 16 -1 (-2050 3250)(-1925 3250);
WIRE 16 -1 (-1925 3300)(-1925 3250);
WIRE 16 -1 (-1925 3350)(-1925 3300);
WIRE 16 -1 (-1925 3300)(-2050 3300);
WIRE 16 -1 (-1925 3400)(-1925 3350);
WIRE 16 -1 (-1925 3350)(-2050 3350);
WIRE 16 -1 (-1925 3450)(-1925 3400);
WIRE 16 -1 (-1925 3400)(-2050 3400);
WIRE 16 -1 (-1925 3500)(-1925 3450);
WIRE 16 -1 (-1925 3450)(-2050 3450);
WIRE 16 -1 (-1925 3550)(-1925 3500);
WIRE 16 -1 (-1925 3500)(-2050 3500);
WIRE 16 -1 (-1925 3600)(-1925 3550);
WIRE 16 -1 (-1925 3550)(-2050 3550);
WIRE 16 -1 (-2050 3600)(-1925 3600);
WIRE 16 -1 (-1925 3650)(-1925 3600);
WIRE 16 -1 (-2050 3650)(-1925 3650);
WIRE 16 -1 (-1925 3700)(-1925 3650);
WIRE 16 -1 (-1925 3750)(-1925 3700);
WIRE 16 -1 (-1925 3700)(-2050 3700);
WIRE 16 -1 (-1925 3800)(-1925 3750);
WIRE 16 -1 (-1925 3750)(-2050 3750);
WIRE 16 -1 (-1925 3850)(-1925 3800);
WIRE 16 -1 (-1925 3800)(-2050 3800);
WIRE 16 -1 (-1925 3900)(-1925 3850);
WIRE 16 -1 (-1925 3850)(-2050 3850);
WIRE 16 -1 (-1925 3950)(-1925 3900);
WIRE 16 -1 (-1925 3900)(-2050 3900);
WIRE 16 -1 (-1925 4000)(-1925 3950);
WIRE 16 -1 (-1925 3950)(-2050 3950);
WIRE 16 -1 (-2050 4000)(-1925 4000);
WIRE 16 -1 (-1925 4050)(-1925 4000);
WIRE 16 -1 (-2050 4050)(-1925 4050);
WIRE 16 -1 (-1925 4100)(-1925 4050);
WIRE 16 -1 (-1925 4150)(-1925 4100);
WIRE 16 -1 (-1925 4100)(-2050 4100);
WIRE 16 -1 (-1925 4200)(-1925 4150);
WIRE 16 -1 (-1925 4150)(-2050 4150);
WIRE 16 -1 (-1925 4250)(-1925 4200);
WIRE 16 -1 (-1925 4200)(-2050 4200);
WIRE 16 -1 (-1925 4300)(-1925 4250);
WIRE 16 -1 (-1925 4250)(-2050 4250);
WIRE 16 -1 (-1925 4350)(-1925 4300);
WIRE 16 -1 (-1925 4300)(-2050 4300);
WIRE 16 -1 (-1925 4400)(-1925 4350);
WIRE 16 -1 (-1925 4350)(-2050 4350);
WIRE 16 -1 (-2050 4400)(-1925 4400);
WIRE 16 -1 (-1925 4450)(-1925 4400);
WIRE 16 -1 (-2050 4450)(-1925 4450);
WIRE 16 -1 (-1925 4500)(-1925 4450);
WIRE 16 -1 (-1925 4550)(-1925 4500);
WIRE 16 -1 (-1925 4500)(-2050 4500);
WIRE 16 -1 (-1925 4600)(-1925 4550);
WIRE 16 -1 (-1925 4550)(-2050 4550);
WIRE 16 -1 (-1925 4650)(-1925 4600);
WIRE 16 -1 (-1925 4600)(-2050 4600);
WIRE 16 -1 (-1925 4700)(-1925 4650);
WIRE 16 -1 (-1925 4650)(-2050 4650);
WIRE 16 -1 (-1925 4750)(-1925 4700);
WIRE 16 -1 (-1925 4700)(-2050 4700);
WIRE 16 -1 (-1925 4800)(-1925 4750);
WIRE 16 -1 (-1925 4750)(-2050 4750);
WIRE 16 -1 (-2050 4800)(-1925 4800);
WIRE 16 -1 (-1925 4850)(-1925 4800);
WIRE 16 -1 (-2050 4850)(-1925 4850);
WIRE 16 -1 (-1925 4900)(-1925 4850);
WIRE 16 -1 (-1925 4950)(-1925 4900);
WIRE 16 -1 (-1925 4900)(-2050 4900);
WIRE 16 -1 (-1925 5000)(-1925 4950);
WIRE 16 -1 (-1925 4950)(-2050 4950);
WIRE 16 -1 (-1925 5050)(-1925 5000);
WIRE 16 -1 (-1925 5000)(-2050 5000);
WIRE 16 -1 (-1925 5100)(-1925 5050);
WIRE 16 -1 (-1925 5050)(-2050 5050);
WIRE 16 -1 (-1925 5150)(-1925 5100);
WIRE 16 -1 (-1925 5100)(-2050 5100);
WIRE 16 -1 (-1925 5200)(-1925 5150);
WIRE 16 -1 (-1925 5150)(-2050 5150);
WIRE 16 -1 (-2050 5200)(-1925 5200);
WIRE 16 -1 (-1925 5250)(-1925 5200);
WIRE 16 -1 (-2050 5250)(-1925 5250);
WIRE 16 -1 (-1925 5300)(-1925 5250);
WIRE 16 -1 (-1925 5350)(-1925 5300);
WIRE 16 -1 (-1925 5300)(-2050 5300);
WIRE 16 -1 (-1925 5400)(-1925 5350);
WIRE 16 -1 (-1925 5350)(-2050 5350);
WIRE 16 -1 (-1925 5450)(-1925 5400);
WIRE 16 -1 (-1925 5400)(-2050 5400);
WIRE 16 -1 (-1925 5500)(-1925 5450);
WIRE 16 -1 (-1925 5450)(-2050 5450);
WIRE 16 -1 (-1925 5550)(-1925 5500);
WIRE 16 -1 (-1925 5500)(-2050 5500);
WIRE 16 -1 (-1925 5600)(-1925 5550);
WIRE 16 -1 (-1925 5550)(-2050 5550);
WIRE 16 -1 (-2050 5600)(-1925 5600);
WIRE 16 -1 (-1925 5650)(-1925 5600);
WIRE 16 -1 (-2050 5650)(-1925 5650);
WIRE 16 -1 (-1925 5700)(-1925 5650);
WIRE 16 -1 (-1925 5750)(-1925 5700);
WIRE 16 -1 (-1925 5700)(-2050 5700);
WIRE 16 -1 (-1925 5800)(-1925 5750);
WIRE 16 -1 (-1925 5750)(-2050 5750);
WIRE 16 -1 (-1925 5850)(-1925 5800);
WIRE 16 -1 (-1925 5800)(-2050 5800);
WIRE 16 -1 (-1925 5900)(-1925 5850);
WIRE 16 -1 (-1925 5850)(-2050 5850);
WIRE 16 -1 (-1925 5950)(-1925 5900);
WIRE 16 -1 (-1925 5900)(-2050 5900);
WIRE 16 -1 (-1925 6000)(-1925 5950);
WIRE 16 -1 (-1925 5950)(-2050 5950);
WIRE 16 -1 (-2050 6000)(-1925 6000);
WIRE 16 -1 (-1925 6050)(-1925 6000);
WIRE 16 -1 (-2050 6050)(-1925 6050);
WIRE 16 -1 (-1925 6100)(-1925 6050);
WIRE 16 -1 (-2050 6100)(-1925 6100);
WIRE 16 -1 (-1925 6150)(-1925 6100);
WIRE 16 -1 (-2050 6150)(-1925 6150);
WIRE 16 -1 (-1925 6200)(-1925 6150);
WIRE 16 -1 (-2050 6200)(-1925 6200);
WIRE 16 -1 (-1925 6250)(-1925 6200);
WIRE 16 -1 (-2050 6250)(-1925 6250);
WIRE 16 -1 (-1925 6300)(-1925 6250);
WIRE 16 -1 (-2050 6300)(-1925 6300);
WIRE 16 -1 (-1925 6350)(-1925 6300);
WIRE 16 -1 (-2050 6350)(-1925 6350);
WIRE 16 -1 (-1925 6400)(-1925 6350);
WIRE 16 -1 (-1925 6450)(-1925 6400);
WIRE 16 -1 (-1925 6400)(-2050 6400);
WIRE 16 -1 (-1925 6450)(-2050 6450);
WIRE 16 -1 (-1525 550)(-1625 550);
WIRE 16 -1 (-1625 600)(-1625 550);
WIRE 16 -1 (-1625 550)(-1625 500);
WIRE 16 -1 (-1525 600)(-1625 600);
WIRE 16 -1 (-1625 650)(-1625 600);
WIRE 16 -1 (-1525 650)(-1625 650);
WIRE 16 -1 (-1625 700)(-1625 650);
WIRE 16 -1 (-1525 700)(-1625 700);
WIRE 16 -1 (-1625 750)(-1625 700);
WIRE 16 -1 (-1525 750)(-1625 750);
WIRE 16 -1 (-1625 800)(-1625 750);
WIRE 16 -1 (-1525 800)(-1625 800);
WIRE 16 -1 (-1625 850)(-1625 800);
WIRE 16 -1 (-1525 850)(-1625 850);
WIRE 16 -1 (-1625 900)(-1625 850);
WIRE 16 -1 (-1525 900)(-1625 900);
WIRE 16 -1 (-1625 950)(-1625 900);
WIRE 16 -1 (-1525 950)(-1625 950);
WIRE 16 -1 (-1625 1000)(-1625 950);
WIRE 16 -1 (-1625 1050)(-1625 1000);
WIRE 16 -1 (-1525 1000)(-1625 1000);
WIRE 16 -1 (-1625 1050)(-1525 1050);
WIRE 16 -1 (-1625 1100)(-1625 1050);
WIRE 16 -1 (-1625 1100)(-1525 1100);
WIRE 16 -1 (-1625 1150)(-1625 1100);
WIRE 16 -1 (-1625 1150)(-1525 1150);
WIRE 16 -1 (-1625 1200)(-1625 1150);
WIRE 16 -1 (-1625 1200)(-1525 1200);
WIRE 16 -1 (-1625 1250)(-1625 1200);
WIRE 16 -1 (-1625 1250)(-1525 1250);
WIRE 16 -1 (-1625 1300)(-1625 1250);
WIRE 16 -1 (-1625 1300)(-1525 1300);
WIRE 16 -1 (-1625 1350)(-1625 1300);
WIRE 16 -1 (-1525 1350)(-1625 1350);
WIRE 16 -1 (-1625 1400)(-1625 1350);
WIRE 16 -1 (-1525 1400)(-1625 1400);
WIRE 16 -1 (-1625 1450)(-1625 1400);
WIRE 16 -1 (-1625 1450)(-1525 1450);
WIRE 16 -1 (-1625 1500)(-1625 1450);
WIRE 16 -1 (-1625 1500)(-1525 1500);
WIRE 16 -1 (-1625 1550)(-1625 1500);
WIRE 16 -1 (-1625 1550)(-1525 1550);
WIRE 16 -1 (-1625 1600)(-1625 1550);
WIRE 16 -1 (-1625 1600)(-1525 1600);
WIRE 16 -1 (-1625 1650)(-1625 1600);
WIRE 16 -1 (-1625 1650)(-1525 1650);
WIRE 16 -1 (-1625 1700)(-1625 1650);
WIRE 16 -1 (-1625 1700)(-1525 1700);
WIRE 16 -1 (-1625 1750)(-1625 1700);
WIRE 16 -1 (-1525 1750)(-1625 1750);
WIRE 16 -1 (-1625 1800)(-1625 1750);
WIRE 16 -1 (-1525 1800)(-1625 1800);
WIRE 16 -1 (-1625 1850)(-1625 1800);
WIRE 16 -1 (-1625 1850)(-1525 1850);
WIRE 16 -1 (-1625 1900)(-1625 1850);
WIRE 16 -1 (-1625 1900)(-1525 1900);
WIRE 16 -1 (-1625 1950)(-1625 1900);
WIRE 16 -1 (-1625 1950)(-1525 1950);
WIRE 16 -1 (-1625 2000)(-1625 1950);
WIRE 16 -1 (-1625 2050)(-1625 2000);
WIRE 16 -1 (-1625 2000)(-1525 2000);
WIRE 16 -1 (-1625 2050)(-1525 2050);
WIRE 16 -1 (-1625 2100)(-1625 2050);
WIRE 16 -1 (-1625 2100)(-1525 2100);
WIRE 16 -1 (-1625 2150)(-1625 2100);
WIRE 16 -1 (-1525 2150)(-1625 2150);
WIRE 16 -1 (-1625 2200)(-1625 2150);
WIRE 16 -1 (-1525 2200)(-1625 2200);
WIRE 16 -1 (-1625 2250)(-1625 2200);
WIRE 16 -1 (-1625 2250)(-1525 2250);
WIRE 16 -1 (-1625 2300)(-1625 2250);
WIRE 16 -1 (-1625 2300)(-1525 2300);
WIRE 16 -1 (-1625 2350)(-1625 2300);
WIRE 16 -1 (-1625 2350)(-1525 2350);
WIRE 16 -1 (-1625 2400)(-1625 2350);
WIRE 16 -1 (-1625 2400)(-1525 2400);
WIRE 16 -1 (-1625 2450)(-1625 2400);
WIRE 16 -1 (-1625 2450)(-1525 2450);
WIRE 16 -1 (-1625 2500)(-1625 2450);
WIRE 16 -1 (-1625 2500)(-1525 2500);
WIRE 16 -1 (-1625 2550)(-1625 2500);
WIRE 16 -1 (-1525 2550)(-1625 2550);
WIRE 16 -1 (-1625 2600)(-1625 2550);
WIRE 16 -1 (-1525 2600)(-1625 2600);
WIRE 16 -1 (-1625 2650)(-1625 2600);
WIRE 16 -1 (-1625 2650)(-1525 2650);
WIRE 16 -1 (-1625 2700)(-1625 2650);
WIRE 16 -1 (-1625 2700)(-1525 2700);
WIRE 16 -1 (-1625 2750)(-1625 2700);
WIRE 16 -1 (-1625 2750)(-1525 2750);
WIRE 16 -1 (-1625 2800)(-1625 2750);
WIRE 16 -1 (-1625 2800)(-1525 2800);
WIRE 16 -1 (-1625 2850)(-1625 2800);
WIRE 16 -1 (-1625 2850)(-1525 2850);
WIRE 16 -1 (-1625 2900)(-1625 2850);
WIRE 16 -1 (-1625 2900)(-1525 2900);
WIRE 16 -1 (-1625 2950)(-1625 2900);
WIRE 16 -1 (-1525 2950)(-1625 2950);
WIRE 16 -1 (-1625 3000)(-1625 2950);
WIRE 16 -1 (-1525 3000)(-1625 3000);
WIRE 16 -1 (-1625 3050)(-1625 3000);
WIRE 16 -1 (-1625 3100)(-1625 3050);
WIRE 16 -1 (-1625 3050)(-1525 3050);
WIRE 16 -1 (-1625 3100)(-1525 3100);
WIRE 16 -1 (-1625 3150)(-1625 3100);
WIRE 16 -1 (-1625 3150)(-1525 3150);
WIRE 16 -1 (-1625 3200)(-1625 3150);
WIRE 16 -1 (-1625 3200)(-1525 3200);
WIRE 16 -1 (-1625 3250)(-1625 3200);
WIRE 16 -1 (-1625 3250)(-1525 3250);
WIRE 16 -1 (-1625 3300)(-1625 3250);
WIRE 16 -1 (-1625 3300)(-1525 3300);
WIRE 16 -1 (-1625 3350)(-1625 3300);
WIRE 16 -1 (-1525 3350)(-1625 3350);
WIRE 16 -1 (-1625 3400)(-1625 3350);
WIRE 16 -1 (-1525 3400)(-1625 3400);
WIRE 16 -1 (-1625 3450)(-1625 3400);
WIRE 16 -1 (-1625 3450)(-1525 3450);
WIRE 16 -1 (-1625 3500)(-1625 3450);
WIRE 16 -1 (-1625 3500)(-1525 3500);
WIRE 16 -1 (-1625 3550)(-1625 3500);
WIRE 16 -1 (-1625 3550)(-1525 3550);
WIRE 16 -1 (-1625 3600)(-1625 3550);
WIRE 16 -1 (-1625 3600)(-1525 3600);
WIRE 16 -1 (-1625 3650)(-1625 3600);
WIRE 16 -1 (-1625 3650)(-1525 3650);
WIRE 16 -1 (-1625 3700)(-1625 3650);
WIRE 16 -1 (-1625 3700)(-1525 3700);
WIRE 16 -1 (-1625 3750)(-1625 3700);
WIRE 16 -1 (-1525 3750)(-1625 3750);
WIRE 16 -1 (-1625 3800)(-1625 3750);
WIRE 16 -1 (-1525 3800)(-1625 3800);
WIRE 16 -1 (-1625 3850)(-1625 3800);
WIRE 16 -1 (-1625 3850)(-1525 3850);
WIRE 16 -1 (-1625 3900)(-1625 3850);
WIRE 16 -1 (-1625 3900)(-1525 3900);
WIRE 16 -1 (-1625 3950)(-1625 3900);
WIRE 16 -1 (-1625 3950)(-1525 3950);
WIRE 16 -1 (-1625 4000)(-1625 3950);
WIRE 16 -1 (-1625 4000)(-1525 4000);
WIRE 16 -1 (-1625 4050)(-1625 4000);
WIRE 16 -1 (-1625 4100)(-1625 4050);
WIRE 16 -1 (-1625 4050)(-1525 4050);
WIRE 16 -1 (-1625 4100)(-1525 4100);
WIRE 16 -1 (-1625 4150)(-1625 4100);
WIRE 16 -1 (-1525 4150)(-1625 4150);
WIRE 16 -1 (-1625 4200)(-1625 4150);
WIRE 16 -1 (-1525 4200)(-1625 4200);
WIRE 16 -1 (-1625 4250)(-1625 4200);
WIRE 16 -1 (-1625 4250)(-1525 4250);
WIRE 16 -1 (-1625 4300)(-1625 4250);
WIRE 16 -1 (-1625 4300)(-1525 4300);
WIRE 16 -1 (-1625 4350)(-1625 4300);
WIRE 16 -1 (-1625 4350)(-1525 4350);
WIRE 16 -1 (-1625 4400)(-1625 4350);
WIRE 16 -1 (-1625 4400)(-1525 4400);
WIRE 16 -1 (-1625 4450)(-1625 4400);
WIRE 16 -1 (-1625 4450)(-1525 4450);
WIRE 16 -1 (-1625 4500)(-1625 4450);
WIRE 16 -1 (-1625 4500)(-1525 4500);
WIRE 16 -1 (-1625 4550)(-1625 4500);
WIRE 16 -1 (-1525 4550)(-1625 4550);
WIRE 16 -1 (-1625 4600)(-1625 4550);
WIRE 16 -1 (-1525 4600)(-1625 4600);
WIRE 16 -1 (-1625 4650)(-1625 4600);
WIRE 16 -1 (-1625 4650)(-1525 4650);
WIRE 16 -1 (-1625 4700)(-1625 4650);
WIRE 16 -1 (-1625 4700)(-1525 4700);
WIRE 16 -1 (-1625 4750)(-1625 4700);
WIRE 16 -1 (-1625 4750)(-1525 4750);
WIRE 16 -1 (-1625 4800)(-1625 4750);
WIRE 16 -1 (-1625 4800)(-1525 4800);
WIRE 16 -1 (-1625 4850)(-1625 4800);
WIRE 16 -1 (-1625 4850)(-1525 4850);
WIRE 16 -1 (-1625 4900)(-1625 4850);
WIRE 16 -1 (-1625 4900)(-1525 4900);
WIRE 16 -1 (-1625 4950)(-1625 4900);
WIRE 16 -1 (-1525 4950)(-1625 4950);
WIRE 16 -1 (-1625 5000)(-1625 4950);
WIRE 16 -1 (-1525 5000)(-1625 5000);
WIRE 16 -1 (-1625 5050)(-1625 5000);
WIRE 16 -1 (-1625 5050)(-1525 5050);
WIRE 16 -1 (-1625 5100)(-1625 5050);
WIRE 16 -1 (-1625 5150)(-1625 5100);
WIRE 16 -1 (-1625 5100)(-1525 5100);
WIRE 16 -1 (-1625 5150)(-1525 5150);
WIRE 16 -1 (-1625 5200)(-1625 5150);
WIRE 16 -1 (-1625 5200)(-1525 5200);
WIRE 16 -1 (-1625 5250)(-1625 5200);
WIRE 16 -1 (-1625 5250)(-1525 5250);
WIRE 16 -1 (-1625 5300)(-1625 5250);
WIRE 16 -1 (-1625 5300)(-1525 5300);
WIRE 16 -1 (-1625 5350)(-1625 5300);
WIRE 16 -1 (-1525 5350)(-1625 5350);
WIRE 16 -1 (-1625 5400)(-1625 5350);
WIRE 16 -1 (-1525 5400)(-1625 5400);
WIRE 16 -1 (-1625 5450)(-1625 5400);
WIRE 16 -1 (-1625 5450)(-1525 5450);
WIRE 16 -1 (-1625 5500)(-1625 5450);
WIRE 16 -1 (-1625 5500)(-1525 5500);
WIRE 16 -1 (-1625 5550)(-1625 5500);
WIRE 16 -1 (-1625 5550)(-1525 5550);
WIRE 16 -1 (-1625 5600)(-1625 5550);
WIRE 16 -1 (-1625 5600)(-1525 5600);
WIRE 16 -1 (-1625 5650)(-1625 5600);
WIRE 16 -1 (-1625 5650)(-1525 5650);
WIRE 16 -1 (-1625 5700)(-1625 5650);
WIRE 16 -1 (-1625 5700)(-1525 5700);
WIRE 16 -1 (-1625 5750)(-1625 5700);
WIRE 16 -1 (-1525 5750)(-1625 5750);
WIRE 16 -1 (-1625 5800)(-1625 5750);
WIRE 16 -1 (-1525 5800)(-1625 5800);
WIRE 16 -1 (-1625 5850)(-1625 5800);
WIRE 16 -1 (-1625 5850)(-1525 5850);
WIRE 16 -1 (-1625 5900)(-1625 5850);
WIRE 16 -1 (-1625 5900)(-1525 5900);
WIRE 16 -1 (-1625 5950)(-1625 5900);
WIRE 16 -1 (-1625 5950)(-1525 5950);
WIRE 16 -1 (-1625 6000)(-1625 5950);
WIRE 16 -1 (-1625 6000)(-1525 6000);
WIRE 16 -1 (-1625 6050)(-1625 6000);
WIRE 16 -1 (-1625 6050)(-1525 6050);
WIRE 16 -1 (-1625 6100)(-1625 6050);
WIRE 16 -1 (-1625 6150)(-1625 6100);
WIRE 16 -1 (-1625 6100)(-1525 6100);
WIRE 16 -1 (-1525 6150)(-1625 6150);
WIRE 16 -1 (-1625 6200)(-1625 6150);
WIRE 16 -1 (-1525 6200)(-1625 6200);
WIRE 16 -1 (-1625 6250)(-1625 6200);
WIRE 16 -1 (-1625 6250)(-1525 6250);
WIRE 16 -1 (-1625 6300)(-1625 6250);
WIRE 16 -1 (-1625 6300)(-1525 6300);
WIRE 16 -1 (-1625 6350)(-1625 6300);
WIRE 16 -1 (-1625 6350)(-1525 6350);
WIRE 16 -1 (-1625 6400)(-1625 6350);
WIRE 16 -1 (-1625 6400)(-1525 6400);
WIRE 16 -1 (-1625 6450)(-1625 6400);
WIRE 16 -1 (-1625 6450)(-1525 6450);
WIRE 16 -1 (-300 600)(-300 550);
WIRE 16 -1 (-300 650)(-300 600);
WIRE 16 -1 (-300 600)(-425 600);
WIRE 16 -1 (-300 550)(-300 525);
WIRE 16 -1 (-300 550)(-425 550);
WIRE 16 -1 (-300 700)(-300 650);
WIRE 16 -1 (-300 650)(-425 650);
WIRE 16 -1 (-300 750)(-300 700);
WIRE 16 -1 (-300 700)(-425 700);
WIRE 16 -1 (-300 800)(-300 750);
WIRE 16 -1 (-300 750)(-425 750);
WIRE 16 -1 (-300 850)(-300 800);
WIRE 16 -1 (-425 800)(-300 800);
WIRE 16 -1 (-425 850)(-300 850);
WIRE 16 -1 (-300 900)(-300 850);
WIRE 16 -1 (-300 950)(-300 900);
WIRE 16 -1 (-300 900)(-425 900);
WIRE 16 -1 (-300 1000)(-300 950);
WIRE 16 -1 (-300 950)(-425 950);
WIRE 16 -1 (-300 1050)(-300 1000);
WIRE 16 -1 (-300 1000)(-425 1000);
WIRE 16 -1 (-300 1100)(-300 1050);
WIRE 16 -1 (-300 1050)(-425 1050);
WIRE 16 -1 (-300 1150)(-300 1100);
WIRE 16 -1 (-300 1100)(-425 1100);
WIRE 16 -1 (-300 1200)(-300 1150);
WIRE 16 -1 (-300 1150)(-425 1150);
WIRE 16 -1 (-425 1200)(-300 1200);
WIRE 16 -1 (-300 1250)(-300 1200);
WIRE 16 -1 (-425 1250)(-300 1250);
WIRE 16 -1 (-300 1300)(-300 1250);
WIRE 16 -1 (-300 1350)(-300 1300);
WIRE 16 -1 (-300 1300)(-425 1300);
WIRE 16 -1 (-300 1400)(-300 1350);
WIRE 16 -1 (-300 1350)(-425 1350);
WIRE 16 -1 (-300 1450)(-300 1400);
WIRE 16 -1 (-300 1400)(-425 1400);
WIRE 16 -1 (-300 1500)(-300 1450);
WIRE 16 -1 (-300 1450)(-425 1450);
WIRE 16 -1 (-300 1550)(-300 1500);
WIRE 16 -1 (-300 1500)(-425 1500);
WIRE 16 -1 (-300 1600)(-300 1550);
WIRE 16 -1 (-300 1550)(-425 1550);
WIRE 16 -1 (-425 1600)(-300 1600);
WIRE 16 -1 (-300 1650)(-300 1600);
WIRE 16 -1 (-425 1650)(-300 1650);
WIRE 16 -1 (-300 1700)(-300 1650);
WIRE 16 -1 (-300 1750)(-300 1700);
WIRE 16 -1 (-300 1700)(-425 1700);
WIRE 16 -1 (-300 1800)(-300 1750);
WIRE 16 -1 (-300 1750)(-425 1750);
WIRE 16 -1 (-300 1850)(-300 1800);
WIRE 16 -1 (-300 1800)(-425 1800);
WIRE 16 -1 (-300 1900)(-300 1850);
WIRE 16 -1 (-300 1850)(-425 1850);
WIRE 16 -1 (-300 1950)(-300 1900);
WIRE 16 -1 (-300 1900)(-425 1900);
WIRE 16 -1 (-300 2000)(-300 1950);
WIRE 16 -1 (-300 1950)(-425 1950);
WIRE 16 -1 (-425 2000)(-300 2000);
WIRE 16 -1 (-300 2050)(-300 2000);
WIRE 16 -1 (-300 2100)(-300 2050);
WIRE 16 -1 (-425 2050)(-300 2050);
WIRE 16 -1 (-300 2150)(-300 2100);
WIRE 16 -1 (-300 2100)(-425 2100);
WIRE 16 -1 (-300 2200)(-300 2150);
WIRE 16 -1 (-300 2150)(-425 2150);
WIRE 16 -1 (-300 2250)(-300 2200);
WIRE 16 -1 (-300 2200)(-425 2200);
WIRE 16 -1 (-300 2300)(-300 2250);
WIRE 16 -1 (-300 2250)(-425 2250);
WIRE 16 -1 (-300 2350)(-300 2300);
WIRE 16 -1 (-300 2300)(-425 2300);
WIRE 16 -1 (-300 2400)(-300 2350);
WIRE 16 -1 (-300 2350)(-425 2350);
WIRE 16 -1 (-425 2400)(-300 2400);
WIRE 16 -1 (-300 2450)(-300 2400);
WIRE 16 -1 (-425 2450)(-300 2450);
WIRE 16 -1 (-300 2500)(-300 2450);
WIRE 16 -1 (-300 2550)(-300 2500);
WIRE 16 -1 (-300 2500)(-425 2500);
WIRE 16 -1 (-300 2600)(-300 2550);
WIRE 16 -1 (-300 2550)(-425 2550);
WIRE 16 -1 (-300 2650)(-300 2600);
WIRE 16 -1 (-300 2600)(-425 2600);
WIRE 16 -1 (-300 2700)(-300 2650);
WIRE 16 -1 (-300 2650)(-425 2650);
WIRE 16 -1 (-300 2750)(-300 2700);
WIRE 16 -1 (-300 2700)(-425 2700);
WIRE 16 -1 (-300 2800)(-300 2750);
WIRE 16 -1 (-300 2750)(-425 2750);
WIRE 16 -1 (-425 2800)(-300 2800);
WIRE 16 -1 (-300 2850)(-300 2800);
WIRE 16 -1 (-300 2900)(-300 2850);
WIRE 16 -1 (-425 2850)(-300 2850);
WIRE 16 -1 (-300 2950)(-300 2900);
WIRE 16 -1 (-300 2900)(-425 2900);
WIRE 16 -1 (-300 3000)(-300 2950);
WIRE 16 -1 (-300 2950)(-425 2950);
WIRE 16 -1 (-300 3050)(-300 3000);
WIRE 16 -1 (-300 3000)(-425 3000);
WIRE 16 -1 (-300 3100)(-300 3050);
WIRE 16 -1 (-300 3050)(-425 3050);
WIRE 16 -1 (-300 3150)(-300 3100);
WIRE 16 -1 (-300 3100)(-425 3100);
WIRE 16 -1 (-300 3200)(-300 3150);
WIRE 16 -1 (-300 3150)(-425 3150);
WIRE 16 -1 (-425 3200)(-300 3200);
WIRE 16 -1 (-300 3250)(-300 3200);
WIRE 16 -1 (-425 3250)(-300 3250);
WIRE 16 -1 (-300 3300)(-300 3250);
WIRE 16 -1 (-300 3350)(-300 3300);
WIRE 16 -1 (-300 3300)(-425 3300);
WIRE 16 -1 (-300 3400)(-300 3350);
WIRE 16 -1 (-300 3350)(-425 3350);
WIRE 16 -1 (-300 3450)(-300 3400);
WIRE 16 -1 (-300 3400)(-425 3400);
WIRE 16 -1 (-300 3500)(-300 3450);
WIRE 16 -1 (-300 3450)(-425 3450);
WIRE 16 -1 (-300 3550)(-300 3500);
WIRE 16 -1 (-300 3500)(-425 3500);
WIRE 16 -1 (-300 3600)(-300 3550);
WIRE 16 -1 (-300 3550)(-425 3550);
WIRE 16 -1 (-300 3650)(-300 3600);
WIRE 16 -1 (-425 3600)(-300 3600);
WIRE 16 -1 (-425 3650)(-300 3650);
WIRE 16 -1 (-300 3700)(-300 3650);
WIRE 16 -1 (-300 3750)(-300 3700);
WIRE 16 -1 (-300 3700)(-425 3700);
WIRE 16 -1 (-300 3800)(-300 3750);
WIRE 16 -1 (-300 3750)(-425 3750);
WIRE 16 -1 (-300 3850)(-300 3800);
WIRE 16 -1 (-300 3800)(-425 3800);
WIRE 16 -1 (-300 3900)(-300 3850);
WIRE 16 -1 (-300 3850)(-425 3850);
WIRE 16 -1 (-300 3950)(-300 3900);
WIRE 16 -1 (-300 3900)(-425 3900);
WIRE 16 -1 (-300 4000)(-300 3950);
WIRE 16 -1 (-300 3950)(-425 3950);
WIRE 16 -1 (-425 4000)(-300 4000);
WIRE 16 -1 (-300 4050)(-300 4000);
WIRE 16 -1 (-425 4050)(-300 4050);
WIRE 16 -1 (-300 4100)(-300 4050);
WIRE 16 -1 (-300 4150)(-300 4100);
WIRE 16 -1 (-300 4100)(-425 4100);
WIRE 16 -1 (-300 4200)(-300 4150);
WIRE 16 -1 (-300 4150)(-425 4150);
WIRE 16 -1 (-300 4250)(-300 4200);
WIRE 16 -1 (-300 4200)(-425 4200);
WIRE 16 -1 (-300 4300)(-300 4250);
WIRE 16 -1 (-300 4250)(-425 4250);
WIRE 16 -1 (-300 4350)(-300 4300);
WIRE 16 -1 (-300 4300)(-425 4300);
WIRE 16 -1 (-300 4400)(-300 4350);
WIRE 16 -1 (-300 4350)(-425 4350);
WIRE 16 -1 (-300 4450)(-300 4400);
WIRE 16 -1 (-425 4400)(-300 4400);
WIRE 16 -1 (-425 4450)(-300 4450);
WIRE 16 -1 (-300 4500)(-300 4450);
WIRE 16 -1 (-300 4550)(-300 4500);
WIRE 16 -1 (-300 4500)(-425 4500);
WIRE 16 -1 (-300 4600)(-300 4550);
WIRE 16 -1 (-300 4550)(-425 4550);
WIRE 16 -1 (-300 4650)(-300 4600);
WIRE 16 -1 (-300 4600)(-425 4600);
WIRE 16 -1 (-300 4700)(-300 4650);
WIRE 16 -1 (-300 4650)(-425 4650);
WIRE 16 -1 (-300 4750)(-300 4700);
WIRE 16 -1 (-300 4700)(-425 4700);
WIRE 16 -1 (-300 4800)(-300 4750);
WIRE 16 -1 (-300 4750)(-425 4750);
WIRE 16 -1 (-425 4800)(-300 4800);
WIRE 16 -1 (-300 4850)(-300 4800);
WIRE 16 -1 (-425 4850)(-300 4850);
WIRE 16 -1 (-300 4900)(-300 4850);
WIRE 16 -1 (-300 4950)(-300 4900);
WIRE 16 -1 (-300 4900)(-425 4900);
WIRE 16 -1 (-300 5000)(-300 4950);
WIRE 16 -1 (-300 4950)(-425 4950);
WIRE 16 -1 (-300 5050)(-300 5000);
WIRE 16 -1 (-300 5000)(-425 5000);
WIRE 16 -1 (-300 5100)(-300 5050);
WIRE 16 -1 (-300 5050)(-425 5050);
WIRE 16 -1 (-300 5150)(-300 5100);
WIRE 16 -1 (-300 5100)(-425 5100);
WIRE 16 -1 (-300 5200)(-300 5150);
WIRE 16 -1 (-300 5150)(-425 5150);
WIRE 16 -1 (-425 5200)(-300 5200);
WIRE 16 -1 (-300 5250)(-300 5200);
WIRE 16 -1 (-425 5250)(-300 5250);
WIRE 16 -1 (-300 5300)(-300 5250);
WIRE 16 -1 (-300 5350)(-300 5300);
WIRE 16 -1 (-300 5300)(-425 5300);
WIRE 16 -1 (-300 5400)(-300 5350);
WIRE 16 -1 (-300 5350)(-425 5350);
WIRE 16 -1 (-300 5450)(-300 5400);
WIRE 16 -1 (-300 5400)(-425 5400);
WIRE 16 -1 (-300 5500)(-300 5450);
WIRE 16 -1 (-300 5450)(-425 5450);
WIRE 16 -1 (-300 5550)(-300 5500);
WIRE 16 -1 (-300 5500)(-425 5500);
WIRE 16 -1 (-300 5600)(-300 5550);
WIRE 16 -1 (-300 5550)(-425 5550);
WIRE 16 -1 (-425 5600)(-300 5600);
WIRE 16 -1 (-300 5650)(-300 5600);
WIRE 16 -1 (-300 5700)(-300 5650);
WIRE 16 -1 (-425 5650)(-300 5650);
WIRE 16 -1 (-300 5750)(-300 5700);
WIRE 16 -1 (-300 5700)(-425 5700);
WIRE 16 -1 (-300 5800)(-300 5750);
WIRE 16 -1 (-300 5750)(-425 5750);
WIRE 16 -1 (-300 5850)(-300 5800);
WIRE 16 -1 (-300 5800)(-425 5800);
WIRE 16 -1 (-300 5900)(-300 5850);
WIRE 16 -1 (-300 5850)(-425 5850);
WIRE 16 -1 (-300 5950)(-300 5900);
WIRE 16 -1 (-300 5900)(-425 5900);
WIRE 16 -1 (-300 6000)(-300 5950);
WIRE 16 -1 (-300 5950)(-425 5950);
WIRE 16 -1 (-425 6000)(-300 6000);
WIRE 16 -1 (-300 6050)(-300 6000);
WIRE 16 -1 (-425 6050)(-300 6050);
WIRE 16 -1 (-300 6100)(-300 6050);
WIRE 16 -1 (-425 6100)(-300 6100);
WIRE 16 -1 (-300 6150)(-300 6100);
WIRE 16 -1 (-300 6200)(-300 6150);
WIRE 16 -1 (-425 6150)(-300 6150);
WIRE 16 -1 (-425 6200)(-300 6200);
WIRE 16 -1 (-300 6250)(-300 6200);
WIRE 16 -1 (-425 6250)(-300 6250);
WIRE 16 -1 (-300 6300)(-300 6250);
WIRE 16 -1 (-425 6300)(-300 6300);
WIRE 16 -1 (-300 6350)(-300 6300);
WIRE 16 -1 (-425 6350)(-300 6350);
WIRE 16 -1 (-300 6400)(-300 6350);
WIRE 16 -1 (-300 6400)(-425 6400);
WIRE 16 -1 (-300 6450)(-300 6400);
WIRE 16 -1 (-300 6450)(-425 6450);
DOT 1 (-9250 475);
DOT 1 (-9250 525);
DOT 1 (-9250 625);
DOT 1 (-9250 575);
DOT 1 (-9250 775);
DOT 1 (-9250 725);
DOT 1 (-9250 825);
DOT 1 (-9250 875);
DOT 1 (-9250 925);
DOT 1 (-9250 1025);
DOT 1 (-9250 975);
DOT 1 (-9250 1175);
DOT 1 (-9250 1125);
DOT 1 (-9250 1075);
DOT 1 (-9250 1225);
DOT 1 (-9250 1275);
DOT 1 (-9250 1425);
DOT 1 (-9250 1375);
DOT 1 (-9250 1325);
DOT 1 (-9250 1525);
DOT 1 (-9250 1475);
DOT 1 (-9250 1675);
DOT 1 (-9250 1625);
DOT 1 (-9250 1575);
DOT 1 (-9250 1725);
DOT 1 (-9250 1775);
DOT 1 (-9250 1825);
DOT 1 (-9250 1925);
DOT 1 (-9250 1875);
DOT 1 (-9250 1975);
DOT 1 (-9250 2025);
DOT 1 (-9250 2075);
DOT 1 (-9250 2175);
DOT 1 (-9250 2125);
DOT 1 (-9250 2325);
DOT 1 (-9250 2275);
DOT 1 (-9250 2225);
DOT 1 (-9250 2375);
DOT 1 (-9250 2425);
DOT 1 (-9250 2575);
DOT 1 (-9250 2525);
DOT 1 (-9250 2475);
DOT 1 (-9250 2675);
DOT 1 (-9250 2625);
DOT 1 (-9250 2725);
DOT 1 (-9250 2825);
DOT 1 (-9250 2775);
DOT 1 (-9250 2875);
DOT 1 (-9250 2925);
DOT 1 (-9250 2975);
DOT 1 (-9250 3075);
DOT 1 (-9250 3025);
DOT 1 (-9250 3175);
DOT 1 (-9250 3125);
DOT 1 (-9250 3225);
DOT 1 (-9250 3275);
DOT 1 (-9250 3325);
DOT 1 (-9250 3475);
DOT 1 (-9250 3425);
DOT 1 (-9250 3375);
DOT 1 (-9250 3575);
DOT 1 (-9250 3525);
DOT 1 (-9250 3725);
DOT 1 (-9250 3675);
DOT 1 (-9250 3625);
DOT 1 (-9250 3775);
DOT 1 (-9250 3825);
DOT 1 (-9250 3875);
DOT 1 (-9250 3975);
DOT 1 (-9250 3925);
DOT 1 (-9250 4075);
DOT 1 (-9250 4025);
DOT 1 (-9250 4125);
DOT 1 (-9250 4225);
DOT 1 (-9250 4175);
DOT 1 (-9250 4375);
DOT 1 (-9250 4325);
DOT 1 (-9250 4275);
DOT 1 (-9250 4425);
DOT 1 (-9250 4475);
DOT 1 (-9250 4625);
DOT 1 (-9250 4575);
DOT 1 (-9250 4525);
DOT 1 (-9250 4725);
DOT 1 (-9250 4675);
DOT 1 (-9250 4875);
DOT 1 (-9250 4825);
DOT 1 (-9250 4775);
DOT 1 (-9250 4925);
DOT 1 (-9250 4975);
DOT 1 (-9250 5025);
DOT 1 (-9250 5125);
DOT 1 (-9250 5075);
DOT 1 (-9250 5225);
DOT 1 (-9250 5175);
DOT 1 (-9250 5275);
DOT 1 (-9250 5375);
DOT 1 (-9250 5325);
DOT 1 (-9250 5525);
DOT 1 (-9250 5475);
DOT 1 (-9250 5425);
DOT 1 (-9250 5625);
DOT 1 (-9250 5575);
DOT 1 (-9250 5775);
DOT 1 (-9250 5725);
DOT 1 (-9250 5675);
DOT 1 (-9250 5825);
DOT 1 (-9250 5875);
DOT 1 (-9250 5925);
DOT 1 (-9250 6025);
DOT 1 (-9250 5975);
DOT 1 (-9250 6075);
DOT 1 (-9250 6125);
DOT 1 (-9250 6175);
DOT 1 (-9250 6225);
DOT 1 (-9250 6275);
DOT 1 (-9250 6325);
DOT 1 (-9250 675);
DOT 1 (-7900 475);
DOT 1 (-7900 525);
DOT 1 (-7900 975);
DOT 1 (-7900 1025);
DOT 1 (-7900 925);
DOT 1 (-7900 875);
DOT 1 (-7900 825);
DOT 1 (-7900 725);
DOT 1 (-7900 775);
DOT 1 (-7900 675);
DOT 1 (-7900 575);
DOT 1 (-7900 625);
DOT 1 (-7900 1325);
DOT 1 (-7900 1125);
DOT 1 (-7900 1525);
DOT 1 (-7900 1475);
DOT 1 (-7900 1425);
DOT 1 (-7900 1375);
DOT 1 (-7900 1275);
DOT 1 (-7900 1225);
DOT 1 (-7900 1175);
DOT 1 (-7900 1075);
DOT 1 (-7900 2025);
DOT 1 (-7900 1975);
DOT 1 (-7900 1875);
DOT 1 (-7900 1925);
DOT 1 (-7900 1825);
DOT 1 (-7900 1775);
DOT 1 (-7900 1725);
DOT 1 (-7900 1675);
DOT 1 (-7900 1575);
DOT 1 (-7900 2075);
DOT 1 (-7900 2575);
DOT 1 (-7900 2475);
DOT 1 (-7900 2525);
DOT 1 (-7900 2425);
DOT 1 (-7900 2375);
DOT 1 (-7900 2325);
DOT 1 (-7900 2225);
DOT 1 (-7900 2275);
DOT 1 (-7900 2175);
DOT 1 (-7900 3075);
DOT 1 (-7900 2775);
DOT 1 (-7900 2825);
DOT 1 (-7900 2725);
DOT 1 (-7900 2675);
DOT 1 (-7900 2625);
DOT 1 (-7900 3575);
DOT 1 (-7900 3525);
DOT 1 (-7900 3475);
DOT 1 (-7900 3375);
DOT 1 (-7900 3425);
DOT 1 (-7900 3325);
DOT 1 (-7900 3275);
DOT 1 (-7900 3225);
DOT 1 (-7900 3175);
DOT 1 (-7900 3125);
DOT 1 (-7900 4075);
DOT 1 (-7900 3925);
DOT 1 (-7900 3975);
DOT 1 (-7900 3875);
DOT 1 (-7900 3825);
DOT 1 (-7900 3775);
DOT 1 (-7900 3725);
DOT 1 (-7900 3625);
DOT 1 (-7900 3675);
DOT 1 (-7900 4125);
DOT 1 (-7900 4625);
DOT 1 (-7900 4525);
DOT 1 (-7900 4575);
DOT 1 (-7900 4475);
DOT 1 (-7900 4425);
DOT 1 (-7900 4375);
DOT 1 (-7900 4275);
DOT 1 (-7900 4325);
DOT 1 (-7900 4175);
DOT 1 (-7900 4225);
DOT 1 (-7900 5075);
DOT 1 (-7900 5125);
DOT 1 (-7900 5025);
DOT 1 (-7900 4975);
DOT 1 (-7900 4925);
DOT 1 (-7900 4875);
DOT 1 (-7900 4775);
DOT 1 (-7900 4825);
DOT 1 (-7900 4725);
DOT 1 (-7900 4675);
DOT 1 (-7900 5625);
DOT 1 (-7900 5575);
DOT 1 (-7900 5525);
DOT 1 (-7900 5425);
DOT 1 (-7900 5475);
DOT 1 (-7900 5325);
DOT 1 (-7900 5375);
DOT 1 (-7900 5275);
DOT 1 (-7900 5225);
DOT 1 (-7900 5175);
DOT 1 (-7900 6125);
DOT 1 (-7900 6075);
DOT 1 (-7900 5975);
DOT 1 (-7900 6025);
DOT 1 (-7900 5925);
DOT 1 (-7900 5825);
DOT 1 (-7900 5775);
DOT 1 (-7900 5675);
DOT 1 (-7900 5725);
DOT 1 (-7900 5875);
DOT 1 (-7900 6175);
DOT 1 (-7900 6325);
DOT 1 (-7900 6225);
DOT 1 (-7900 6275);
DOT 1 (-7900 4025);
DOT 1 (-7900 3025);
DOT 1 (-7900 2975);
DOT 1 (-7900 2925);
DOT 1 (-7900 2875);
DOT 1 (-7900 1625);
DOT 1 (-7900 2125);
DOT 1 (-7725 500);
DOT 1 (-7725 550);
DOT 1 (-7725 600);
DOT 1 (-7725 650);
DOT 1 (-7725 750);
DOT 1 (-7725 700);
DOT 1 (-7725 800);
DOT 1 (-7725 850);
DOT 1 (-7725 900);
DOT 1 (-7725 1000);
DOT 1 (-7725 950);
DOT 1 (-7725 1050);
DOT 1 (-7725 1100);
DOT 1 (-7725 1150);
DOT 1 (-7725 1200);
DOT 1 (-7725 1250);
DOT 1 (-7725 1300);
DOT 1 (-7725 1400);
DOT 1 (-7725 1350);
DOT 1 (-7725 1450);
DOT 1 (-7725 1500);
DOT 1 (-7725 1550);
DOT 1 (-7725 1650);
DOT 1 (-7725 1600);
DOT 1 (-7725 1700);
DOT 1 (-7725 1750);
DOT 1 (-7725 1800);
DOT 1 (-7725 1900);
DOT 1 (-7725 1850);
DOT 1 (-7725 1950);
DOT 1 (-7725 2000);
DOT 1 (-7725 2050);
DOT 1 (-6375 500);
DOT 1 (-6375 550);
DOT 1 (-6375 650);
DOT 1 (-6375 600);
DOT 1 (-6375 700);
DOT 1 (-6375 750);
DOT 1 (-6375 800);
DOT 1 (-6375 850);
DOT 1 (-6375 900);
DOT 1 (-6375 950);
DOT 1 (-6375 1000);
DOT 1 (-6375 1050);
DOT 1 (-6375 1100);
DOT 1 (-6375 1150);
DOT 1 (-6375 1200);
DOT 1 (-6375 1250);
DOT 1 (-6375 1300);
DOT 1 (-6375 1400);
DOT 1 (-6375 1350);
DOT 1 (-6375 1450);
DOT 1 (-6375 1500);
DOT 1 (-6375 1550);
DOT 1 (-6375 1650);
DOT 1 (-6375 1600);
DOT 1 (-6375 1700);
DOT 1 (-6375 1750);
DOT 1 (-6375 1800);
DOT 1 (-6375 1850);
DOT 1 (-6375 1900);
DOT 1 (-6375 1950);
DOT 1 (-6375 2000);
DOT 1 (-6375 2050);
DOT 1 (-7725 2100);
DOT 1 (-7725 2150);
DOT 1 (-7725 2200);
DOT 1 (-7725 2300);
DOT 1 (-7725 2250);
DOT 1 (-7725 2350);
DOT 1 (-7725 2400);
DOT 1 (-7725 2450);
DOT 1 (-7725 2550);
DOT 1 (-7725 2500);
DOT 1 (-7725 2600);
DOT 1 (-7725 2650);
DOT 1 (-7725 2700);
DOT 1 (-7725 2800);
DOT 1 (-7725 2750);
DOT 1 (-7725 2850);
DOT 1 (-7725 2900);
DOT 1 (-7725 2950);
DOT 1 (-7725 3050);
DOT 1 (-7725 3000);
DOT 1 (-7725 3100);
DOT 1 (-7725 3150);
DOT 1 (-7725 3200);
DOT 1 (-7725 3250);
DOT 1 (-7725 3300);
DOT 1 (-7725 3350);
DOT 1 (-7725 3450);
DOT 1 (-7725 3400);
DOT 1 (-7725 3500);
DOT 1 (-7725 3550);
DOT 1 (-7725 3600);
DOT 1 (-7725 3700);
DOT 1 (-7725 3650);
DOT 1 (-7725 3750);
DOT 1 (-7725 3800);
DOT 1 (-7725 3850);
DOT 1 (-7725 3950);
DOT 1 (-7725 3900);
DOT 1 (-7725 4000);
DOT 1 (-7725 4050);
DOT 1 (-7725 4100);
DOT 1 (-6375 2200);
DOT 1 (-6375 2100);
DOT 1 (-6375 2300);
DOT 1 (-6375 2250);
DOT 1 (-6375 2350);
DOT 1 (-6375 2400);
DOT 1 (-6375 2450);
DOT 1 (-6375 2550);
DOT 1 (-6375 2500);
DOT 1 (-6375 2650);
DOT 1 (-6375 2700);
DOT 1 (-6375 2600);
DOT 1 (-6375 2750);
DOT 1 (-6375 2800);
DOT 1 (-6375 2850);
DOT 1 (-6375 2900);
DOT 1 (-6375 2950);
DOT 1 (-6375 3000);
DOT 1 (-6375 3050);
DOT 1 (-6375 3100);
DOT 1 (-6375 3150);
DOT 1 (-6375 3200);
DOT 1 (-6375 3250);
DOT 1 (-6375 3300);
DOT 1 (-6375 3350);
DOT 1 (-6375 3400);
DOT 1 (-6375 3450);
DOT 1 (-6375 3500);
DOT 1 (-6375 3550);
DOT 1 (-6375 3600);
DOT 1 (-6375 3700);
DOT 1 (-6375 3750);
DOT 1 (-6375 3800);
DOT 1 (-6375 3850);
DOT 1 (-6375 3900);
DOT 1 (-6375 3950);
DOT 1 (-6375 4000);
DOT 1 (-6375 4050);
DOT 1 (-6375 4100);
DOT 1 (-7725 4200);
DOT 1 (-7725 4150);
DOT 1 (-7725 4250);
DOT 1 (-7725 4300);
DOT 1 (-7725 4350);
DOT 1 (-7725 4400);
DOT 1 (-7725 4450);
DOT 1 (-7725 4500);
DOT 1 (-7725 4600);
DOT 1 (-7725 4550);
DOT 1 (-7725 4650);
DOT 1 (-7725 4700);
DOT 1 (-7725 4750);
DOT 1 (-7725 4850);
DOT 1 (-7725 4800);
DOT 1 (-7725 4900);
DOT 1 (-7725 4950);
DOT 1 (-7725 5000);
DOT 1 (-7725 5050);
DOT 1 (-7725 5100);
DOT 1 (-7725 5150);
DOT 1 (-7725 5200);
DOT 1 (-7725 5250);
DOT 1 (-7725 5300);
DOT 1 (-7725 5350);
DOT 1 (-7725 5400);
DOT 1 (-7725 5500);
DOT 1 (-7725 5450);
DOT 1 (-7725 5550);
DOT 1 (-7725 5600);
DOT 1 (-7725 5650);
DOT 1 (-7725 5750);
DOT 1 (-7725 5700);
DOT 1 (-7725 5800);
DOT 1 (-7725 5850);
DOT 1 (-7725 5900);
DOT 1 (-7725 5950);
DOT 1 (-7725 6000);
DOT 1 (-7725 6050);
DOT 1 (-7725 6150);
DOT 1 (-7725 6100);
DOT 1 (-6375 4200);
DOT 1 (-6375 4150);
DOT 1 (-6375 4250);
DOT 1 (-6375 4350);
DOT 1 (-6375 4300);
DOT 1 (-6375 4400);
DOT 1 (-6375 4450);
DOT 1 (-6375 4500);
DOT 1 (-6375 4600);
DOT 1 (-6375 4550);
DOT 1 (-6375 4700);
DOT 1 (-6375 4750);
DOT 1 (-6375 4650);
DOT 1 (-6375 4850);
DOT 1 (-6375 4800);
DOT 1 (-6375 4900);
DOT 1 (-6375 4950);
DOT 1 (-6375 5000);
DOT 1 (-6375 5050);
DOT 1 (-6375 5100);
DOT 1 (-6375 5150);
DOT 1 (-6375 5200);
DOT 1 (-6375 5250);
DOT 1 (-6375 5300);
DOT 1 (-6375 5400);
DOT 1 (-6375 5350);
DOT 1 (-6375 5500);
DOT 1 (-6375 5450);
DOT 1 (-6375 5550);
DOT 1 (-6375 5600);
DOT 1 (-6375 5650);
DOT 1 (-6375 5750);
DOT 1 (-6375 5700);
DOT 1 (-6375 5800);
DOT 1 (-6375 5850);
DOT 1 (-6375 5900);
DOT 1 (-6375 5950);
DOT 1 (-6375 6000);
DOT 1 (-6375 6050);
DOT 1 (-6375 6100);
DOT 1 (-6375 6150);
DOT 1 (-7725 6200);
DOT 1 (-7725 6250);
DOT 1 (-6375 6250);
DOT 1 (-6375 6200);
DOT 1 (-6375 2150);
DOT 1 (-6250 525);
DOT 1 (-6250 625);
DOT 1 (-6250 575);
DOT 1 (-6250 675);
DOT 1 (-6250 775);
DOT 1 (-6250 725);
DOT 1 (-6250 875);
DOT 1 (-6250 825);
DOT 1 (-6250 925);
DOT 1 (-6250 1025);
DOT 1 (-6250 975);
DOT 1 (-6250 1175);
DOT 1 (-6250 1125);
DOT 1 (-6250 1075);
DOT 1 (-6250 1275);
DOT 1 (-6250 1225);
DOT 1 (-6250 1425);
DOT 1 (-6250 1375);
DOT 1 (-6250 1325);
DOT 1 (-6250 1525);
DOT 1 (-6250 1475);
DOT 1 (-6250 1575);
DOT 1 (-6250 1625);
DOT 1 (-6250 1675);
DOT 1 (-6250 1775);
DOT 1 (-6250 1725);
DOT 1 (-6250 1825);
DOT 1 (-6250 1925);
DOT 1 (-6250 1875);
DOT 1 (-6250 2025);
DOT 1 (-6250 1975);
DOT 1 (-6250 2075);
DOT 1 (-6250 2175);
DOT 1 (-6250 2125);
DOT 1 (-6250 2325);
DOT 1 (-6250 2275);
DOT 1 (-6250 2225);
DOT 1 (-6250 2425);
DOT 1 (-6250 2375);
DOT 1 (-6250 2575);
DOT 1 (-6250 2525);
DOT 1 (-6250 2475);
DOT 1 (-6250 2675);
DOT 1 (-6250 2625);
DOT 1 (-6250 2725);
DOT 1 (-6250 2825);
DOT 1 (-6250 2775);
DOT 1 (-6250 2925);
DOT 1 (-6250 2875);
DOT 1 (-6250 2975);
DOT 1 (-6250 3075);
DOT 1 (-6250 3025);
DOT 1 (-6250 3175);
DOT 1 (-6250 3125);
DOT 1 (-6250 3225);
DOT 1 (-6250 3325);
DOT 1 (-6250 3275);
DOT 1 (-6250 3475);
DOT 1 (-6250 3425);
DOT 1 (-6250 3375);
DOT 1 (-6250 3575);
DOT 1 (-6250 3525);
DOT 1 (-6250 3725);
DOT 1 (-6250 3625);
DOT 1 (-6250 3825);
DOT 1 (-6250 3775);
DOT 1 (-6250 3875);
DOT 1 (-6250 3975);
DOT 1 (-6250 3925);
DOT 1 (-6250 4075);
DOT 1 (-6250 4025);
DOT 1 (-4900 575);
DOT 1 (-4900 625);
DOT 1 (-4900 675);
DOT 1 (-4900 725);
DOT 1 (-4900 775);
DOT 1 (-4900 875);
DOT 1 (-4900 825);
DOT 1 (-4900 925);
DOT 1 (-4900 1025);
DOT 1 (-4900 975);
DOT 1 (-4900 1175);
DOT 1 (-4900 1075);
DOT 1 (-4900 1125);
DOT 1 (-4900 1275);
DOT 1 (-4900 1225);
DOT 1 (-4900 1325);
DOT 1 (-4900 1375);
DOT 1 (-4900 1425);
DOT 1 (-4900 1475);
DOT 1 (-4900 1525);
DOT 1 (-4900 1675);
DOT 1 (-4900 1625);
DOT 1 (-4900 1575);
DOT 1 (-4900 1775);
DOT 1 (-4900 1725);
DOT 1 (-4900 1825);
DOT 1 (-4900 1875);
DOT 1 (-4900 1925);
DOT 1 (-4900 2025);
DOT 1 (-4900 1975);
DOT 1 (-4900 2075);
DOT 1 (-4900 2125);
DOT 1 (-4900 2175);
DOT 1 (-4900 2275);
DOT 1 (-4900 2225);
DOT 1 (-4900 2325);
DOT 1 (-4900 2425);
DOT 1 (-4900 2375);
DOT 1 (-4900 2575);
DOT 1 (-4900 2525);
DOT 1 (-4900 2475);
DOT 1 (-4900 2625);
DOT 1 (-4900 2675);
DOT 1 (-4900 2725);
DOT 1 (-4900 2825);
DOT 1 (-4900 2775);
DOT 1 (-4900 2875);
DOT 1 (-4900 2925);
DOT 1 (-4900 2975);
DOT 1 (-4900 3075);
DOT 1 (-4900 3025);
DOT 1 (-4900 3175);
DOT 1 (-4900 3125);
DOT 1 (-4900 3225);
DOT 1 (-4900 3275);
DOT 1 (-4900 3325);
DOT 1 (-4900 3375);
DOT 1 (-4900 3425);
DOT 1 (-4900 3475);
DOT 1 (-4900 3525);
DOT 1 (-4900 3575);
DOT 1 (-4900 3675);
DOT 1 (-4900 3625);
DOT 1 (-4900 3725);
DOT 1 (-4900 3825);
DOT 1 (-4900 3775);
DOT 1 (-4900 3875);
DOT 1 (-4900 3925);
DOT 1 (-4900 3975);
DOT 1 (-4900 4075);
DOT 1 (-4900 4025);
DOT 1 (-6250 4125);
DOT 1 (-4900 4125);
DOT 1 (-6250 4175);
DOT 1 (-6250 4225);
DOT 1 (-6250 4325);
DOT 1 (-6250 4375);
DOT 1 (-6250 4275);
DOT 1 (-6250 4475);
DOT 1 (-6250 4425);
DOT 1 (-6250 4575);
DOT 1 (-6250 4625);
DOT 1 (-6250 4525);
DOT 1 (-6250 4725);
DOT 1 (-6250 4675);
DOT 1 (-6250 4775);
DOT 1 (-6250 4825);
DOT 1 (-6250 4875);
DOT 1 (-6250 4925);
DOT 1 (-6250 4975);
DOT 1 (-6250 5025);
DOT 1 (-6250 5075);
DOT 1 (-6250 5125);
DOT 1 (-6250 5175);
DOT 1 (-6250 5225);
DOT 1 (-6250 5275);
DOT 1 (-6250 5375);
DOT 1 (-6250 5525);
DOT 1 (-6250 5475);
DOT 1 (-6250 5425);
DOT 1 (-6250 5625);
DOT 1 (-6250 5575);
DOT 1 (-6250 5775);
DOT 1 (-6250 5725);
DOT 1 (-6250 5675);
DOT 1 (-6250 5875);
DOT 1 (-6250 5825);
DOT 1 (-6250 5925);
DOT 1 (-6250 6025);
DOT 1 (-6250 5975);
DOT 1 (-6250 6125);
DOT 1 (-6250 6075);
DOT 1 (-6250 6175);
DOT 1 (-6250 6275);
DOT 1 (-6250 6225);
DOT 1 (-4900 4175);
DOT 1 (-4900 4225);
DOT 1 (-4900 4325);
DOT 1 (-4900 4275);
DOT 1 (-4900 4375);
DOT 1 (-4900 4475);
DOT 1 (-4900 4425);
DOT 1 (-4900 4625);
DOT 1 (-4900 4575);
DOT 1 (-4900 4525);
DOT 1 (-4900 4675);
DOT 1 (-4900 4725);
DOT 1 (-4900 4775);
DOT 1 (-4900 4825);
DOT 1 (-4900 4875);
DOT 1 (-4900 4975);
DOT 1 (-4900 4925);
DOT 1 (-4900 5025);
DOT 1 (-4900 5125);
DOT 1 (-4900 5075);
DOT 1 (-4900 5225);
DOT 1 (-4900 5175);
DOT 1 (-4900 5275);
DOT 1 (-4900 5325);
DOT 1 (-4900 5375);
DOT 1 (-4900 5475);
DOT 1 (-4900 5425);
DOT 1 (-4900 5525);
DOT 1 (-4900 5575);
DOT 1 (-4900 5625);
DOT 1 (-4900 5725);
DOT 1 (-4900 5675);
DOT 1 (-4900 5775);
DOT 1 (-4900 5875);
DOT 1 (-4900 5825);
DOT 1 (-4900 5925);
DOT 1 (-4900 5975);
DOT 1 (-4900 6025);
DOT 1 (-4900 6075);
DOT 1 (-4900 6175);
DOT 1 (-4900 6225);
DOT 1 (-4900 6275);
DOT 1 (-4750 600);
DOT 1 (-4750 650);
DOT 1 (-4750 750);
DOT 1 (-4750 700);
DOT 1 (-4750 800);
DOT 1 (-4750 850);
DOT 1 (-4750 900);
DOT 1 (-4750 950);
DOT 1 (-4750 1000);
DOT 1 (-4750 1050);
DOT 1 (-4750 1100);
DOT 1 (-4750 1150);
DOT 1 (-4750 1200);
DOT 1 (-4750 1250);
DOT 1 (-4750 1300);
DOT 1 (-4750 1350);
DOT 1 (-4750 1400);
DOT 1 (-4750 1450);
DOT 1 (-4750 1500);
DOT 1 (-4750 1550);
DOT 1 (-4750 1600);
DOT 1 (-4750 1650);
DOT 1 (-4750 1700);
DOT 1 (-4750 1750);
DOT 1 (-4750 1800);
DOT 1 (-4750 1850);
DOT 1 (-4750 1900);
DOT 1 (-4750 1950);
DOT 1 (-4750 2000);
DOT 1 (-4750 2050);
DOT 1 (-4750 2100);
DOT 1 (-4750 2150);
DOT 1 (-4750 2200);
DOT 1 (-4750 2250);
DOT 1 (-4750 2300);
DOT 1 (-4750 2350);
DOT 1 (-4750 2400);
DOT 1 (-4750 2450);
DOT 1 (-4750 2500);
DOT 1 (-4750 2550);
DOT 1 (-4750 2600);
DOT 1 (-4750 2650);
DOT 1 (-4750 2700);
DOT 1 (-4750 2750);
DOT 1 (-4750 2800);
DOT 1 (-4750 2850);
DOT 1 (-4750 2900);
DOT 1 (-4750 2950);
DOT 1 (-4750 3000);
DOT 1 (-4750 3050);
DOT 1 (-4750 3100);
DOT 1 (-4750 3150);
DOT 1 (-4750 3200);
DOT 1 (-4750 3250);
DOT 1 (-4750 3300);
DOT 1 (-4750 3350);
DOT 1 (-4750 3400);
DOT 1 (-4750 3450);
DOT 1 (-4750 3500);
DOT 1 (-4750 3550);
DOT 1 (-4750 3600);
DOT 1 (-4750 3650);
DOT 1 (-4750 3700);
DOT 1 (-4750 3750);
DOT 1 (-4750 3800);
DOT 1 (-4750 3850);
DOT 1 (-4750 3900);
DOT 1 (-4750 3950);
DOT 1 (-4750 4000);
DOT 1 (-4750 4050);
DOT 1 (-4750 4100);
DOT 1 (-4750 4150);
DOT 1 (-4750 4200);
DOT 1 (-4750 4250);
DOT 1 (-4750 4300);
DOT 1 (-4750 4350);
DOT 1 (-4750 4400);
DOT 1 (-4750 4450);
DOT 1 (-4750 4500);
DOT 1 (-4750 4550);
DOT 1 (-4750 4600);
DOT 1 (-4750 4650);
DOT 1 (-4750 4700);
DOT 1 (-4750 4750);
DOT 1 (-4750 4800);
DOT 1 (-4750 4850);
DOT 1 (-4750 4900);
DOT 1 (-4750 4950);
DOT 1 (-4750 5000);
DOT 1 (-4750 5050);
DOT 1 (-4750 5100);
DOT 1 (-4750 5150);
DOT 1 (-4750 5200);
DOT 1 (-4750 5250);
DOT 1 (-4750 5300);
DOT 1 (-4750 5350);
DOT 1 (-4750 5400);
DOT 1 (-4750 5450);
DOT 1 (-4750 5500);
DOT 1 (-4750 5550);
DOT 1 (-4750 5600);
DOT 1 (-4750 5650);
DOT 1 (-4750 5700);
DOT 1 (-4750 5750);
DOT 1 (-4750 5800);
DOT 1 (-4750 5850);
DOT 1 (-4750 5900);
DOT 1 (-4750 5950);
DOT 1 (-4750 6000);
DOT 1 (-4750 6050);
DOT 1 (-4750 6100);
DOT 1 (-4750 6150);
DOT 1 (-4750 6200);
DOT 1 (-4750 6250);
DOT 1 (-4750 6300);
DOT 1 (-4750 6350);
DOT 1 (-3400 600);
DOT 1 (-3400 650);
DOT 1 (-3400 700);
DOT 1 (-3400 750);
DOT 1 (-3400 800);
DOT 1 (-3400 850);
DOT 1 (-3400 900);
DOT 1 (-3400 950);
DOT 1 (-3400 1000);
DOT 1 (-3400 1050);
DOT 1 (-3400 1100);
DOT 1 (-3400 1150);
DOT 1 (-3400 1200);
DOT 1 (-3400 1250);
DOT 1 (-3400 1300);
DOT 1 (-3400 1400);
DOT 1 (-3400 1350);
DOT 1 (-3400 1450);
DOT 1 (-3400 1500);
DOT 1 (-3400 1550);
DOT 1 (-3400 1600);
DOT 1 (-3400 1650);
DOT 1 (-3400 1700);
DOT 1 (-3400 1750);
DOT 1 (-3400 1800);
DOT 1 (-3400 1900);
DOT 1 (-3400 1850);
DOT 1 (-3400 1950);
DOT 1 (-3400 2000);
DOT 1 (-3400 2050);
DOT 1 (-3400 2100);
DOT 1 (-3400 2150);
DOT 1 (-3400 2200);
DOT 1 (-3400 2250);
DOT 1 (-3400 2300);
DOT 1 (-3400 2350);
DOT 1 (-3400 2400);
DOT 1 (-3400 2450);
DOT 1 (-3400 2500);
DOT 1 (-3400 2550);
DOT 1 (-3400 2600);
DOT 1 (-3400 2650);
DOT 1 (-3400 2700);
DOT 1 (-3400 2800);
DOT 1 (-3400 2750);
DOT 1 (-3400 2850);
DOT 1 (-3400 2900);
DOT 1 (-3400 2950);
DOT 1 (-3400 3000);
DOT 1 (-3400 3050);
DOT 1 (-3400 3100);
DOT 1 (-3400 3150);
DOT 1 (-3400 3200);
DOT 1 (-3400 3250);
DOT 1 (-3400 3300);
DOT 1 (-3400 3450);
DOT 1 (-3400 3400);
DOT 1 (-3400 3500);
DOT 1 (-3400 3550);
DOT 1 (-3400 3600);
DOT 1 (-3400 3650);
DOT 1 (-3400 3700);
DOT 1 (-3400 3750);
DOT 1 (-3400 3800);
DOT 1 (-3400 3850);
DOT 1 (-3400 3950);
DOT 1 (-3400 3900);
DOT 1 (-3400 4000);
DOT 1 (-3400 4050);
DOT 1 (-3400 4100);
DOT 1 (-3400 4150);
DOT 1 (-3400 4200);
DOT 1 (-3400 4250);
DOT 1 (-3400 4300);
DOT 1 (-3400 4350);
DOT 1 (-3400 4400);
DOT 1 (-3400 4450);
DOT 1 (-3400 4500);
DOT 1 (-3400 4550);
DOT 1 (-3400 4600);
DOT 1 (-3400 4650);
DOT 1 (-3400 4700);
DOT 1 (-3400 4750);
DOT 1 (-3400 4850);
DOT 1 (-3400 4800);
DOT 1 (-3400 4900);
DOT 1 (-3400 4950);
DOT 1 (-3400 5000);
DOT 1 (-3400 5050);
DOT 1 (-3400 5100);
DOT 1 (-3400 5150);
DOT 1 (-3400 5200);
DOT 1 (-3400 5250);
DOT 1 (-3400 5300);
DOT 1 (-3400 5350);
DOT 1 (-3400 5400);
DOT 1 (-3400 5450);
DOT 1 (-3400 5500);
DOT 1 (-3400 5550);
DOT 1 (-3400 5600);
DOT 1 (-3400 5650);
DOT 1 (-3400 5700);
DOT 1 (-3400 5750);
DOT 1 (-3400 5800);
DOT 1 (-3400 5850);
DOT 1 (-3400 5900);
DOT 1 (-3400 6000);
DOT 1 (-3400 5950);
DOT 1 (-3400 6050);
DOT 1 (-3400 6100);
DOT 1 (-3400 6150);
DOT 1 (-3400 6200);
DOT 1 (-3400 6250);
DOT 1 (-3400 6300);
DOT 1 (-3400 6350);
DOT 1 (-6375 3650);
DOT 1 (-6250 3675);
DOT 1 (-3400 3350);
DOT 1 (-3250 550);
DOT 1 (-3250 600);
DOT 1 (-3250 650);
DOT 1 (-3250 700);
DOT 1 (-3250 750);
DOT 1 (-3250 800);
DOT 1 (-3250 850);
DOT 1 (-3250 900);
DOT 1 (-3250 950);
DOT 1 (-3250 1000);
DOT 1 (-3250 1050);
DOT 1 (-3250 1100);
DOT 1 (-3250 1150);
DOT 1 (-3250 1300);
DOT 1 (-3250 1250);
DOT 1 (-3250 1200);
DOT 1 (-3250 1350);
DOT 1 (-3250 1400);
DOT 1 (-3250 1550);
DOT 1 (-3250 1500);
DOT 1 (-3250 1450);
DOT 1 (-3250 1600);
DOT 1 (-3250 1650);
DOT 1 (-3250 1700);
DOT 1 (-3250 1800);
DOT 1 (-3250 1750);
DOT 1 (-3250 1850);
DOT 1 (-3250 1900);
DOT 1 (-3250 1950);
DOT 1 (-3250 2050);
DOT 1 (-3250 2000);
DOT 1 (-3250 2100);
DOT 1 (-3250 2150);
DOT 1 (-3250 2200);
DOT 1 (-3250 2250);
DOT 1 (-3250 2300);
DOT 1 (-3250 2350);
DOT 1 (-3250 2400);
DOT 1 (-3250 2450);
DOT 1 (-3250 2500);
DOT 1 (-3250 2550);
DOT 1 (-3250 2600);
DOT 1 (-3250 2650);
DOT 1 (-3250 2700);
DOT 1 (-3250 2750);
DOT 1 (-3250 2800);
DOT 1 (-3250 2850);
DOT 1 (-3250 2900);
DOT 1 (-3250 2950);
DOT 1 (-3250 3000);
DOT 1 (-3250 3050);
DOT 1 (-3250 3100);
DOT 1 (-3250 3150);
DOT 1 (-3250 3200);
DOT 1 (-3250 3350);
DOT 1 (-3250 3300);
DOT 1 (-3250 3250);
DOT 1 (-3250 3400);
DOT 1 (-3250 3450);
DOT 1 (-3250 3600);
DOT 1 (-3250 3550);
DOT 1 (-3250 3500);
DOT 1 (-3250 3650);
DOT 1 (-3250 3700);
DOT 1 (-3250 3750);
DOT 1 (-3250 3850);
DOT 1 (-3250 3800);
DOT 1 (-3250 3900);
DOT 1 (-3250 3950);
DOT 1 (-3250 4000);
DOT 1 (-3250 4100);
DOT 1 (-3250 4050);
DOT 1 (-1925 600);
DOT 1 (-1925 700);
DOT 1 (-1925 800);
DOT 1 (-1925 900);
DOT 1 (-1925 1000);
DOT 1 (-1925 1050);
DOT 1 (-1925 1100);
DOT 1 (-1925 1150);
DOT 1 (-1925 1200);
DOT 1 (-1925 1250);
DOT 1 (-1925 1300);
DOT 1 (-1925 1400);
DOT 1 (-1925 1350);
DOT 1 (-1925 1450);
DOT 1 (-1925 1500);
DOT 1 (-1925 1550);
DOT 1 (-1925 1600);
DOT 1 (-1925 1650);
DOT 1 (-1925 1700);
DOT 1 (-1925 1750);
DOT 1 (-1925 1800);
DOT 1 (-1925 1900);
DOT 1 (-1925 1850);
DOT 1 (-1925 1950);
DOT 1 (-1925 2000);
DOT 1 (-1925 2050);
DOT 1 (-1925 2100);
DOT 1 (-1925 2150);
DOT 1 (-1925 2200);
DOT 1 (-1925 2300);
DOT 1 (-1925 2250);
DOT 1 (-1925 2350);
DOT 1 (-1925 2400);
DOT 1 (-1925 2450);
DOT 1 (-1925 2550);
DOT 1 (-1925 2500);
DOT 1 (-1925 2600);
DOT 1 (-1925 2650);
DOT 1 (-1925 2700);
DOT 1 (-1925 2800);
DOT 1 (-1925 2750);
DOT 1 (-1925 2850);
DOT 1 (-1925 2900);
DOT 1 (-1925 2950);
DOT 1 (-1925 3050);
DOT 1 (-1925 3000);
DOT 1 (-1925 3100);
DOT 1 (-1925 3150);
DOT 1 (-1925 3200);
DOT 1 (-1925 3250);
DOT 1 (-1925 3300);
DOT 1 (-1925 3350);
DOT 1 (-1925 3450);
DOT 1 (-1925 3400);
DOT 1 (-1925 3500);
DOT 1 (-1925 3550);
DOT 1 (-1925 3600);
DOT 1 (-1925 3650);
DOT 1 (-1925 3700);
DOT 1 (-1925 3750);
DOT 1 (-1925 3800);
DOT 1 (-1925 3850);
DOT 1 (-1925 3950);
DOT 1 (-1925 3900);
DOT 1 (-1925 4000);
DOT 1 (-1925 4050);
DOT 1 (-1925 4100);
DOT 1 (-3250 4150);
DOT 1 (-3250 4200);
DOT 1 (-3250 4250);
DOT 1 (-3250 4350);
DOT 1 (-3250 4300);
DOT 1 (-3250 4400);
DOT 1 (-3250 4450);
DOT 1 (-3250 4500);
DOT 1 (-3250 4550);
DOT 1 (-3250 4600);
DOT 1 (-3250 4650);
DOT 1 (-3250 4700);
DOT 1 (-3250 4750);
DOT 1 (-3250 4800);
DOT 1 (-3250 4850);
DOT 1 (-3250 4900);
DOT 1 (-3250 4950);
DOT 1 (-3250 5000);
DOT 1 (-3250 5050);
DOT 1 (-3250 5100);
DOT 1 (-3250 5150);
DOT 1 (-3250 5200);
DOT 1 (-3250 5250);
DOT 1 (-3250 5400);
DOT 1 (-3250 5350);
DOT 1 (-3250 5300);
DOT 1 (-3250 5450);
DOT 1 (-3250 5500);
DOT 1 (-3250 5650);
DOT 1 (-3250 5600);
DOT 1 (-3250 5550);
DOT 1 (-3250 5700);
DOT 1 (-3250 5750);
DOT 1 (-3250 5900);
DOT 1 (-3250 5850);
DOT 1 (-3250 5800);
DOT 1 (-3250 5950);
DOT 1 (-3250 6000);
DOT 1 (-3250 6050);
DOT 1 (-3250 6150);
DOT 1 (-3250 6100);
DOT 1 (-3250 6250);
DOT 1 (-3250 6200);
DOT 1 (-3250 6300);
DOT 1 (-3250 6350);
DOT 1 (-1925 4200);
DOT 1 (-1925 4150);
DOT 1 (-1925 4250);
DOT 1 (-1925 4300);
DOT 1 (-1925 4350);
DOT 1 (-1925 4400);
DOT 1 (-1925 4450);
DOT 1 (-1925 4500);
DOT 1 (-1925 4600);
DOT 1 (-1925 4550);
DOT 1 (-1925 4650);
DOT 1 (-1925 4700);
DOT 1 (-1925 4750);
DOT 1 (-1925 4850);
DOT 1 (-1925 4800);
DOT 1 (-1925 4900);
DOT 1 (-1925 4950);
DOT 1 (-1925 5000);
DOT 1 (-1925 5100);
DOT 1 (-1925 5050);
DOT 1 (-1925 5150);
DOT 1 (-1925 5200);
DOT 1 (-1925 5250);
DOT 1 (-1925 5300);
DOT 1 (-1925 5350);
DOT 1 (-1925 5400);
DOT 1 (-1925 5500);
DOT 1 (-1925 5450);
DOT 1 (-1925 5550);
DOT 1 (-1925 5600);
DOT 1 (-1925 5650);
DOT 1 (-1925 5700);
DOT 1 (-1925 5750);
DOT 1 (-1925 5800);
DOT 1 (-1925 5850);
DOT 1 (-1925 5900);
DOT 1 (-1925 6000);
DOT 1 (-1925 5950);
DOT 1 (-1925 6050);
DOT 1 (-1925 6100);
DOT 1 (-1925 6150);
DOT 1 (-1925 6250);
DOT 1 (-1925 6200);
DOT 1 (-1925 6300);
DOT 1 (-1925 6350);
DOT 1 (-1925 6400);
DOT 1 (-1925 550);
DOT 1 (-1925 650);
DOT 1 (-1925 750);
DOT 1 (-1925 850);
DOT 1 (-1925 950);
DOT 1 (-4900 6125);
DOT 1 (-1625 650);
DOT 1 (-1625 750);
DOT 1 (-1625 700);
DOT 1 (-1625 800);
DOT 1 (-1625 850);
DOT 1 (-1625 900);
DOT 1 (-1625 1000);
DOT 1 (-1625 950);
DOT 1 (-1625 1050);
DOT 1 (-1625 1100);
DOT 1 (-1625 1150);
DOT 1 (-1625 1200);
DOT 1 (-1625 1250);
DOT 1 (-1625 1300);
DOT 1 (-1625 1400);
DOT 1 (-1625 1350);
DOT 1 (-1625 1450);
DOT 1 (-1625 1500);
DOT 1 (-1625 1550);
DOT 1 (-1625 1650);
DOT 1 (-1625 1600);
DOT 1 (-1625 1700);
DOT 1 (-1625 1750);
DOT 1 (-1625 1800);
DOT 1 (-1625 1900);
DOT 1 (-1625 1850);
DOT 1 (-1625 1950);
DOT 1 (-1625 2000);
DOT 1 (-1625 2050);
DOT 1 (-300 550);
DOT 1 (-300 650);
DOT 1 (-300 600);
DOT 1 (-300 750);
DOT 1 (-300 700);
DOT 1 (-300 800);
DOT 1 (-300 900);
DOT 1 (-300 850);
DOT 1 (-300 950);
DOT 1 (-300 1000);
DOT 1 (-300 1050);
DOT 1 (-300 1150);
DOT 1 (-300 1100);
DOT 1 (-300 1300);
DOT 1 (-300 1250);
DOT 1 (-300 1200);
DOT 1 (-300 1400);
DOT 1 (-300 1350);
DOT 1 (-300 1500);
DOT 1 (-300 1550);
DOT 1 (-300 1450);
DOT 1 (-300 1650);
DOT 1 (-300 1600);
DOT 1 (-300 1700);
DOT 1 (-300 1800);
DOT 1 (-300 1750);
DOT 1 (-300 1900);
DOT 1 (-300 1850);
DOT 1 (-300 1950);
DOT 1 (-300 2050);
DOT 1 (-300 2000);
DOT 1 (-1625 2100);
DOT 1 (-1625 2150);
DOT 1 (-1625 2200);
DOT 1 (-1625 2300);
DOT 1 (-1625 2250);
DOT 1 (-1625 2350);
DOT 1 (-1625 2400);
DOT 1 (-1625 2450);
DOT 1 (-1625 2550);
DOT 1 (-1625 2500);
DOT 1 (-1625 2600);
DOT 1 (-1625 2650);
DOT 1 (-1625 2700);
DOT 1 (-1625 2800);
DOT 1 (-1625 2750);
DOT 1 (-1625 2850);
DOT 1 (-1625 2900);
DOT 1 (-1625 2950);
DOT 1 (-1625 3050);
DOT 1 (-1625 3000);
DOT 1 (-1625 3100);
DOT 1 (-1625 3150);
DOT 1 (-1625 3200);
DOT 1 (-1625 3250);
DOT 1 (-1625 3300);
DOT 1 (-1625 3350);
DOT 1 (-1625 3450);
DOT 1 (-1625 3400);
DOT 1 (-1625 3500);
DOT 1 (-1625 3550);
DOT 1 (-1625 3600);
DOT 1 (-1625 3700);
DOT 1 (-1625 3650);
DOT 1 (-1625 3750);
DOT 1 (-1625 3800);
DOT 1 (-1625 3850);
DOT 1 (-1625 3950);
DOT 1 (-1625 3900);
DOT 1 (-1625 4000);
DOT 1 (-1625 4050);
DOT 1 (-1625 4100);
DOT 1 (-300 2200);
DOT 1 (-300 2150);
DOT 1 (-300 2100);
DOT 1 (-300 2300);
DOT 1 (-300 2250);
DOT 1 (-300 2450);
DOT 1 (-300 2400);
DOT 1 (-300 2350);
DOT 1 (-300 2500);
DOT 1 (-300 2550);
DOT 1 (-300 2650);
DOT 1 (-300 2700);
DOT 1 (-300 2600);
DOT 1 (-300 2750);
DOT 1 (-300 2800);
DOT 1 (-300 2850);
DOT 1 (-300 2950);
DOT 1 (-300 2900);
DOT 1 (-300 3000);
DOT 1 (-300 3050);
DOT 1 (-300 3100);
DOT 1 (-300 3200);
DOT 1 (-300 3150);
DOT 1 (-300 3300);
DOT 1 (-300 3350);
DOT 1 (-300 3250);
DOT 1 (-300 3450);
DOT 1 (-300 3400);
DOT 1 (-300 3550);
DOT 1 (-300 3600);
DOT 1 (-300 3500);
DOT 1 (-300 3700);
DOT 1 (-300 3650);
DOT 1 (-300 3750);
DOT 1 (-300 3850);
DOT 1 (-300 3800);
DOT 1 (-300 3950);
DOT 1 (-300 3900);
DOT 1 (-300 4000);
DOT 1 (-300 4100);
DOT 1 (-300 4050);
DOT 1 (-1625 4200);
DOT 1 (-1625 4150);
DOT 1 (-1625 4250);
DOT 1 (-1625 4300);
DOT 1 (-1625 4350);
DOT 1 (-1625 4400);
DOT 1 (-1625 4450);
DOT 1 (-1625 4500);
DOT 1 (-1625 4600);
DOT 1 (-1625 4550);
DOT 1 (-1625 4650);
DOT 1 (-1625 4700);
DOT 1 (-1625 4750);
DOT 1 (-1625 4850);
DOT 1 (-1625 4800);
DOT 1 (-1625 4900);
DOT 1 (-1625 4950);
DOT 1 (-1625 5000);
DOT 1 (-1625 5100);
DOT 1 (-1625 5050);
DOT 1 (-1625 5150);
DOT 1 (-1625 5200);
DOT 1 (-1625 5250);
DOT 1 (-1625 5300);
DOT 1 (-1625 5350);
DOT 1 (-1625 5400);
DOT 1 (-1625 5500);
DOT 1 (-1625 5450);
DOT 1 (-1625 5550);
DOT 1 (-1625 5600);
DOT 1 (-1625 5650);
DOT 1 (-1625 5750);
DOT 1 (-1625 5700);
DOT 1 (-1625 5800);
DOT 1 (-1625 5850);
DOT 1 (-1625 5900);
DOT 1 (-1625 6000);
DOT 1 (-1625 5950);
DOT 1 (-1625 6050);
DOT 1 (-1625 6100);
DOT 1 (-1625 6150);
DOT 1 (-300 4200);
DOT 1 (-300 4150);
DOT 1 (-300 4250);
DOT 1 (-300 4350);
DOT 1 (-300 4300);
DOT 1 (-300 4500);
DOT 1 (-300 4450);
DOT 1 (-300 4400);
DOT 1 (-300 4550);
DOT 1 (-300 4600);
DOT 1 (-300 4700);
DOT 1 (-300 4750);
DOT 1 (-300 4650);
DOT 1 (-300 4800);
DOT 1 (-300 4850);
DOT 1 (-300 4900);
DOT 1 (-300 5000);
DOT 1 (-300 4950);
DOT 1 (-300 5050);
DOT 1 (-300 5100);
DOT 1 (-300 5150);
DOT 1 (-300 5250);
DOT 1 (-300 5200);
DOT 1 (-300 5350);
DOT 1 (-300 5400);
DOT 1 (-300 5300);
DOT 1 (-300 5500);
DOT 1 (-300 5450);
DOT 1 (-300 5600);
DOT 1 (-300 5650);
DOT 1 (-300 5550);
DOT 1 (-300 5750);
DOT 1 (-300 5700);
DOT 1 (-300 5850);
DOT 1 (-300 5900);
DOT 1 (-300 5800);
DOT 1 (-300 6000);
DOT 1 (-300 5950);
DOT 1 (-300 6050);
DOT 1 (-300 6150);
DOT 1 (-300 6100);
DOT 1 (-1625 6250);
DOT 1 (-1625 6200);
DOT 1 (-1625 6300);
DOT 1 (-1625 6350);
DOT 1 (-1625 6400);
DOT 1 (-300 6250);
DOT 1 (-300 6200);
DOT 1 (-300 6300);
DOT 1 (-300 6400);
DOT 1 (-300 6350);
DOT 1 (-6250 5325);
DOT 1 (-1625 600);
DOT 1 (-1625 550);
QUIT
